FILE_TYPE = MACRO_DRAWING;
SET COLOR_WIRE YELLOW;
SET COLOR_PROP ORANGE;
SET COLOR_DOT WHITE;
SET COLOR_ARC YELLOW;
SET COLOR_BODY GREEN;
SET COLOR_NOTE PURPLE;
SET PROP_DISPLAY VALUE;
SET PAGE_NUMBER P39;
FORCEADD GENOA_SP5..3
(-4750 3675);
FORCEPROP 1 LAST LOCATION U26
J 0
(-5395 6506);
DISPLAY 0.489362 (-5395 6506);
PAINT SKYBLUE (-5395 6506);
FORCEPROP 0 LAST $SEC 3
J 0
(-5375 6550);
DISPLAY 0.680851 (-5375 6550);
PAINT MONO (-5375 6550);
DISPLAY INVISIBLE (-5375 6550);
FORCEPROP 0 LAST CDS_SEC 3
J 0
(-5400 6475);
DISPLAY 1.021277 (-5400 6475);
DISPLAY INVISIBLE (-5400 6475);
FORCEPROP 0 LASTPIN (-5550 3050) $PN BC57
J 2
(-5560 3060);
DISPLAY 0.489362 (-5560 3060);
PAINT MONO (-5560 3060);
FORCEPROP 0 LASTPIN (-5550 3000) $PN BD56
J 2
(-5560 3010);
DISPLAY 0.489362 (-5560 3010);
PAINT MONO (-5560 3010);
FORCEPROP 0 LASTPIN (-5550 1900) $PN BF56
J 2
(-5560 1910);
DISPLAY 0.489362 (-5560 1910);
PAINT MONO (-5560 1910);
FORCEPROP 0 LASTPIN (-5550 1850) $PN BG57
J 2
(-5560 1860);
DISPLAY 0.489362 (-5560 1860);
PAINT MONO (-5560 1860);
FORCEPROP 0 LASTPIN (-5550 2200) $PN AT55
J 2
(-5560 2210);
DISPLAY 0.489362 (-5560 2210);
PAINT MONO (-5560 2210);
FORCEPROP 0 LASTPIN (-5550 2100) $PN AU55
J 2
(-5560 2110);
DISPLAY 0.489362 (-5560 2110);
PAINT MONO (-5560 2110);
FORCEPROP 0 LASTPIN (-5550 2900) $PN AV56
J 2
(-5560 2910);
DISPLAY 0.489362 (-5560 2910);
PAINT MONO (-5560 2910);
FORCEPROP 0 LASTPIN (-5550 2850) $PN AW55
J 2
(-5560 2860);
DISPLAY 0.489362 (-5560 2860);
PAINT MONO (-5560 2860);
FORCEPROP 0 LASTPIN (-5550 2750) $PN BN55
J 2
(-5560 2760);
DISPLAY 0.489362 (-5560 2760);
PAINT MONO (-5560 2760);
FORCEPROP 0 LASTPIN (-5550 1750) $PN AU57
J 2
(-5560 1760);
DISPLAY 0.489362 (-5560 1760);
PAINT MONO (-5560 1760);
FORCEPROP 0 LASTPIN (-5550 1700) $PN AV55
J 2
(-5560 1710);
DISPLAY 0.489362 (-5560 1710);
PAINT MONO (-5560 1710);
FORCEPROP 0 LASTPIN (-5550 1600) $PN BP55
J 2
(-5560 1610);
DISPLAY 0.489362 (-5560 1610);
PAINT MONO (-5560 1610);
FORCEPROP 0 LASTPIN (-5550 3900) $PN AW57
J 2
(-5560 3910);
DISPLAY 0.489362 (-5560 3910);
PAINT MONO (-5560 3910);
FORCEPROP 0 LASTPIN (-5550 3850) $PN AY56
J 2
(-5560 3860);
DISPLAY 0.489362 (-5560 3860);
PAINT MONO (-5560 3860);
FORCEPROP 0 LASTPIN (-5550 3800) $PN AY55
J 2
(-5560 3810);
DISPLAY 0.489362 (-5560 3810);
PAINT MONO (-5560 3810);
FORCEPROP 0 LASTPIN (-5550 3750) $PN BA55
J 2
(-5560 3760);
DISPLAY 0.489362 (-5560 3760);
PAINT MONO (-5560 3760);
FORCEPROP 0 LASTPIN (-5550 3700) $PN BA57
J 2
(-5560 3710);
DISPLAY 0.489362 (-5560 3710);
PAINT MONO (-5560 3710);
FORCEPROP 0 LASTPIN (-5550 3650) $PN BB56
J 2
(-5560 3660);
DISPLAY 0.489362 (-5560 3660);
PAINT MONO (-5560 3660);
FORCEPROP 0 LASTPIN (-5550 3600) $PN BB55
J 2
(-5560 3610);
DISPLAY 0.489362 (-5560 3610);
PAINT MONO (-5560 3610);
FORCEPROP 0 LASTPIN (-3950 2450) $PN AJ57
J 0
(-3940 2460);
DISPLAY 0.489362 (-3940 2460);
PAINT MONO (-3940 2460);
FORCEPROP 0 LASTPIN (-3950 2400) $PN AK55
J 0
(-3940 2410);
DISPLAY 0.489362 (-3940 2410);
PAINT MONO (-3940 2410);
FORCEPROP 0 LASTPIN (-3950 2350) $PN AK56
J 0
(-3940 2360);
DISPLAY 0.489362 (-3940 2360);
PAINT MONO (-3940 2360);
FORCEPROP 0 LASTPIN (-3950 2300) $PN AL55
J 0
(-3940 2310);
DISPLAY 0.489362 (-3940 2310);
PAINT MONO (-3940 2310);
FORCEPROP 0 LASTPIN (-3950 2250) $PN AN57
J 0
(-3940 2260);
DISPLAY 0.489362 (-3940 2260);
PAINT MONO (-3940 2260);
FORCEPROP 0 LASTPIN (-3950 2200) $PN AP55
J 0
(-3940 2210);
DISPLAY 0.489362 (-3940 2210);
PAINT MONO (-3940 2210);
FORCEPROP 0 LASTPIN (-3950 2150) $PN AP56
J 0
(-3940 2160);
DISPLAY 0.489362 (-3940 2160);
PAINT MONO (-3940 2160);
FORCEPROP 0 LASTPIN (-3950 2100) $PN AR55
J 0
(-3940 2110);
DISPLAY 0.489362 (-3940 2110);
PAINT MONO (-3940 2110);
FORCEPROP 0 LASTPIN (-3950 6050) $PN E57
J 0
(-3940 6060);
DISPLAY 0.489362 (-3940 6060);
PAINT MONO (-3940 6060);
FORCEPROP 0 LASTPIN (-3950 6000) $PN F55
J 0
(-3940 6010);
DISPLAY 0.489362 (-3940 6010);
PAINT MONO (-3940 6010);
FORCEPROP 0 LASTPIN (-3950 5950) $PN F56
J 0
(-3940 5960);
DISPLAY 0.489362 (-3940 5960);
PAINT MONO (-3940 5960);
FORCEPROP 0 LASTPIN (-3950 5900) $PN G55
J 0
(-3940 5910);
DISPLAY 0.489362 (-3940 5910);
PAINT MONO (-3940 5910);
FORCEPROP 0 LASTPIN (-3950 5850) $PN J57
J 0
(-3940 5860);
DISPLAY 0.489362 (-3940 5860);
PAINT MONO (-3940 5860);
FORCEPROP 0 LASTPIN (-3950 5800) $PN K55
J 0
(-3940 5810);
DISPLAY 0.489362 (-3940 5810);
PAINT MONO (-3940 5810);
FORCEPROP 0 LASTPIN (-3950 5750) $PN K56
J 0
(-3940 5760);
DISPLAY 0.489362 (-3940 5760);
PAINT MONO (-3940 5760);
FORCEPROP 0 LASTPIN (-3950 5700) $PN L55
J 0
(-3940 5710);
DISPLAY 0.489362 (-3940 5710);
PAINT MONO (-3940 5710);
FORCEPROP 0 LASTPIN (-3950 5600) $PN L57
J 0
(-3940 5610);
DISPLAY 0.489362 (-3940 5610);
PAINT MONO (-3940 5610);
FORCEPROP 0 LASTPIN (-3950 5550) $PN M55
J 0
(-3940 5560);
DISPLAY 0.489362 (-3940 5560);
PAINT MONO (-3940 5560);
FORCEPROP 0 LASTPIN (-3950 5500) $PN M56
J 0
(-3940 5510);
DISPLAY 0.489362 (-3940 5510);
PAINT MONO (-3940 5510);
FORCEPROP 0 LASTPIN (-3950 5450) $PN N55
J 0
(-3940 5460);
DISPLAY 0.489362 (-3940 5460);
PAINT MONO (-3940 5460);
FORCEPROP 0 LASTPIN (-3950 5400) $PN R57
J 0
(-3940 5410);
DISPLAY 0.489362 (-3940 5410);
PAINT MONO (-3940 5410);
FORCEPROP 0 LASTPIN (-3950 5350) $PN T55
J 0
(-3940 5360);
DISPLAY 0.489362 (-3940 5360);
PAINT MONO (-3940 5360);
FORCEPROP 0 LASTPIN (-3950 5300) $PN T56
J 0
(-3940 5310);
DISPLAY 0.489362 (-3940 5310);
PAINT MONO (-3940 5310);
FORCEPROP 0 LASTPIN (-3950 5250) $PN U55
J 0
(-3940 5260);
DISPLAY 0.489362 (-3940 5260);
PAINT MONO (-3940 5260);
FORCEPROP 0 LASTPIN (-3950 5150) $PN U57
J 0
(-3940 5160);
DISPLAY 0.489362 (-3940 5160);
PAINT MONO (-3940 5160);
FORCEPROP 0 LASTPIN (-3950 5100) $PN V55
J 0
(-3940 5110);
DISPLAY 0.489362 (-3940 5110);
PAINT MONO (-3940 5110);
FORCEPROP 0 LASTPIN (-3950 5050) $PN V56
J 0
(-3940 5060);
DISPLAY 0.489362 (-3940 5060);
PAINT MONO (-3940 5060);
FORCEPROP 0 LASTPIN (-3950 5000) $PN W55
J 0
(-3940 5010);
DISPLAY 0.489362 (-3940 5010);
PAINT MONO (-3940 5010);
FORCEPROP 0 LASTPIN (-3950 4950) $PN AA57
J 0
(-3940 4960);
DISPLAY 0.489362 (-3940 4960);
PAINT MONO (-3940 4960);
FORCEPROP 0 LASTPIN (-3950 4900) $PN AB55
J 0
(-3940 4910);
DISPLAY 0.489362 (-3940 4910);
PAINT MONO (-3940 4910);
FORCEPROP 0 LASTPIN (-3950 4850) $PN AB56
J 0
(-3940 4860);
DISPLAY 0.489362 (-3940 4860);
PAINT MONO (-3940 4860);
FORCEPROP 0 LASTPIN (-3950 4800) $PN AC55
J 0
(-3940 4810);
DISPLAY 0.489362 (-3940 4810);
PAINT MONO (-3940 4810);
FORCEPROP 0 LASTPIN (-3950 4700) $PN AC57
J 0
(-3940 4710);
DISPLAY 0.489362 (-3940 4710);
PAINT MONO (-3940 4710);
FORCEPROP 0 LASTPIN (-3950 4650) $PN AD55
J 0
(-3940 4660);
DISPLAY 0.489362 (-3940 4660);
PAINT MONO (-3940 4660);
FORCEPROP 0 LASTPIN (-3950 4600) $PN AD56
J 0
(-3940 4610);
DISPLAY 0.489362 (-3940 4610);
PAINT MONO (-3940 4610);
FORCEPROP 0 LASTPIN (-3950 4550) $PN AE55
J 0
(-3940 4560);
DISPLAY 0.489362 (-3940 4560);
PAINT MONO (-3940 4560);
FORCEPROP 0 LASTPIN (-3950 4500) $PN AG57
J 0
(-3940 4510);
DISPLAY 0.489362 (-3940 4510);
PAINT MONO (-3940 4510);
FORCEPROP 0 LASTPIN (-3950 4450) $PN AH55
J 0
(-3940 4460);
DISPLAY 0.489362 (-3940 4460);
PAINT MONO (-3940 4460);
FORCEPROP 0 LASTPIN (-3950 4400) $PN AH56
J 0
(-3940 4410);
DISPLAY 0.489362 (-3940 4410);
PAINT MONO (-3940 4410);
FORCEPROP 0 LASTPIN (-3950 4350) $PN AJ55
J 0
(-3940 4360);
DISPLAY 0.489362 (-3940 4360);
PAINT MONO (-3940 4360);
FORCEPROP 0 LASTPIN (-5550 6050) $PN G57
J 2
(-5560 6060);
DISPLAY 0.489362 (-5560 6060);
PAINT MONO (-5560 6060);
FORCEPROP 0 LASTPIN (-5550 5950) $PN N57
J 2
(-5560 5960);
DISPLAY 0.489362 (-5560 5960);
PAINT MONO (-5560 5960);
FORCEPROP 0 LASTPIN (-5550 5850) $PN W57
J 2
(-5560 5860);
DISPLAY 0.489362 (-5560 5860);
PAINT MONO (-5560 5860);
FORCEPROP 0 LASTPIN (-5550 5750) $PN AE57
J 2
(-5560 5760);
DISPLAY 0.489362 (-5560 5760);
PAINT MONO (-5560 5760);
FORCEPROP 0 LASTPIN (-5550 5650) $PN AL57
J 2
(-5560 5660);
DISPLAY 0.489362 (-5560 5660);
PAINT MONO (-5560 5660);
FORCEPROP 0 LASTPIN (-5550 5550) $PN J55
J 2
(-5560 5560);
DISPLAY 0.489362 (-5560 5560);
PAINT MONO (-5560 5560);
FORCEPROP 0 LASTPIN (-5550 5450) $PN R55
J 2
(-5560 5460);
DISPLAY 0.489362 (-5560 5460);
PAINT MONO (-5560 5460);
FORCEPROP 0 LASTPIN (-5550 5350) $PN AA55
J 2
(-5560 5360);
DISPLAY 0.489362 (-5560 5360);
PAINT MONO (-5560 5360);
FORCEPROP 0 LASTPIN (-5550 5250) $PN AG55
J 2
(-5560 5260);
DISPLAY 0.489362 (-5560 5260);
PAINT MONO (-5560 5260);
FORCEPROP 0 LASTPIN (-5550 5150) $PN AN55
J 2
(-5560 5160);
DISPLAY 0.489362 (-5560 5160);
PAINT MONO (-5560 5160);
FORCEPROP 0 LASTPIN (-5550 6000) $PN H56
J 2
(-5560 6010);
DISPLAY 0.489362 (-5560 6010);
PAINT MONO (-5560 6010);
FORCEPROP 0 LASTPIN (-5550 5900) $PN P56
J 2
(-5560 5910);
DISPLAY 0.489362 (-5560 5910);
PAINT MONO (-5560 5910);
FORCEPROP 0 LASTPIN (-5550 5800) $PN Y56
J 2
(-5560 5810);
DISPLAY 0.489362 (-5560 5810);
PAINT MONO (-5560 5810);
FORCEPROP 0 LASTPIN (-5550 5700) $PN AF56
J 2
(-5560 5710);
DISPLAY 0.489362 (-5560 5710);
PAINT MONO (-5560 5710);
FORCEPROP 0 LASTPIN (-5550 5600) $PN AM56
J 2
(-5560 5610);
DISPLAY 0.489362 (-5560 5610);
PAINT MONO (-5560 5610);
FORCEPROP 0 LASTPIN (-5550 5500) $PN H55
J 2
(-5560 5510);
DISPLAY 0.489362 (-5560 5510);
PAINT MONO (-5560 5510);
FORCEPROP 0 LASTPIN (-5550 5400) $PN P55
J 2
(-5560 5410);
DISPLAY 0.489362 (-5560 5410);
PAINT MONO (-5560 5410);
FORCEPROP 0 LASTPIN (-5550 5300) $PN Y55
J 2
(-5560 5310);
DISPLAY 0.489362 (-5560 5310);
PAINT MONO (-5560 5310);
FORCEPROP 0 LASTPIN (-5550 5200) $PN AF55
J 2
(-5560 5210);
DISPLAY 0.489362 (-5560 5210);
PAINT MONO (-5560 5210);
FORCEPROP 0 LASTPIN (-5550 5100) $PN AM55
J 2
(-5560 5110);
DISPLAY 0.489362 (-5560 5110);
PAINT MONO (-5560 5110);
FORCEPROP 0 LASTPIN (-5550 2650) $PN BC55
J 2
(-5560 2660);
DISPLAY 0.489362 (-5560 2660);
PAINT MONO (-5560 2660);
FORCEPROP 0 LASTPIN (-5550 2550) $PN BM55
J 2
(-5560 2560);
DISPLAY 0.489362 (-5560 2560);
PAINT MONO (-5560 2560);
FORCEPROP 0 LASTPIN (-5550 2500) $PN BN57
J 2
(-5560 2510);
DISPLAY 0.489362 (-5560 2510);
PAINT MONO (-5560 2510);
FORCEPROP 0 LASTPIN (-5550 2400) $PN BP56
J 2
(-5560 2410);
DISPLAY 0.489362 (-5560 2410);
PAINT MONO (-5560 2410);
FORCEPROP 0 LASTPIN (-5550 1500) $PN BL55
J 2
(-5560 1510);
DISPLAY 0.489362 (-5560 1510);
PAINT MONO (-5560 1510);
FORCEPROP 0 LASTPIN (-5550 1450) $PN BM56
J 2
(-5560 1460);
DISPLAY 0.489362 (-5560 1460);
PAINT MONO (-5560 1460);
FORCEPROP 0 LASTPIN (-5550 1350) $PN BR57
J 2
(-5560 1360);
DISPLAY 0.489362 (-5560 1360);
PAINT MONO (-5560 1360);
FORCEPROP 0 LASTPIN (-5550 3500) $PN BG55
J 2
(-5560 3510);
DISPLAY 0.489362 (-5560 3510);
PAINT MONO (-5560 3510);
FORCEPROP 0 LASTPIN (-5550 3450) $PN BH55
J 2
(-5560 3460);
DISPLAY 0.489362 (-5560 3460);
PAINT MONO (-5560 3460);
FORCEPROP 0 LASTPIN (-5550 3400) $PN BH56
J 2
(-5560 3410);
DISPLAY 0.489362 (-5560 3410);
PAINT MONO (-5560 3410);
FORCEPROP 0 LASTPIN (-5550 3350) $PN BJ57
J 2
(-5560 3360);
DISPLAY 0.489362 (-5560 3360);
PAINT MONO (-5560 3360);
FORCEPROP 0 LASTPIN (-5550 3300) $PN BJ55
J 2
(-5560 3310);
DISPLAY 0.489362 (-5560 3310);
PAINT MONO (-5560 3310);
FORCEPROP 0 LASTPIN (-5550 3250) $PN BK55
J 2
(-5560 3260);
DISPLAY 0.489362 (-5560 3260);
PAINT MONO (-5560 3260);
FORCEPROP 0 LASTPIN (-5550 3200) $PN BK56
J 2
(-5560 3210);
DISPLAY 0.489362 (-5560 3210);
PAINT MONO (-5560 3210);
FORCEPROP 0 LASTPIN (-3950 2000) $PN BY56
J 0
(-3940 2010);
DISPLAY 0.489362 (-3940 2010);
PAINT MONO (-3940 2010);
FORCEPROP 0 LASTPIN (-3950 1950) $PN CA55
J 0
(-3940 1960);
DISPLAY 0.489362 (-3940 1960);
PAINT MONO (-3940 1960);
FORCEPROP 0 LASTPIN (-3950 1900) $PN CA57
J 0
(-3940 1910);
DISPLAY 0.489362 (-3940 1910);
PAINT MONO (-3940 1910);
FORCEPROP 0 LASTPIN (-3950 1850) $PN CB55
J 0
(-3940 1860);
DISPLAY 0.489362 (-3940 1860);
PAINT MONO (-3940 1860);
FORCEPROP 0 LASTPIN (-3950 1800) $PN BT56
J 0
(-3940 1810);
DISPLAY 0.489362 (-3940 1810);
PAINT MONO (-3940 1810);
FORCEPROP 0 LASTPIN (-3950 1750) $PN BU55
J 0
(-3940 1760);
DISPLAY 0.489362 (-3940 1760);
PAINT MONO (-3940 1760);
FORCEPROP 0 LASTPIN (-3950 1700) $PN BU57
J 0
(-3940 1710);
DISPLAY 0.489362 (-3940 1710);
PAINT MONO (-3940 1710);
FORCEPROP 0 LASTPIN (-3950 1650) $PN BV55
J 0
(-3940 1660);
DISPLAY 0.489362 (-3940 1660);
PAINT MONO (-3940 1660);
FORCEPROP 0 LASTPIN (-3950 4250) $PN CB56
J 0
(-3940 4260);
DISPLAY 0.489362 (-3940 4260);
PAINT MONO (-3940 4260);
FORCEPROP 0 LASTPIN (-3950 4200) $PN CC55
J 0
(-3940 4210);
DISPLAY 0.489362 (-3940 4210);
PAINT MONO (-3940 4210);
FORCEPROP 0 LASTPIN (-3950 4150) $PN CC57
J 0
(-3940 4160);
DISPLAY 0.489362 (-3940 4160);
PAINT MONO (-3940 4160);
FORCEPROP 0 LASTPIN (-3950 4100) $PN CD55
J 0
(-3940 4110);
DISPLAY 0.489362 (-3940 4110);
PAINT MONO (-3940 4110);
FORCEPROP 0 LASTPIN (-3950 4050) $PN CF56
J 0
(-3940 4060);
DISPLAY 0.489362 (-3940 4060);
PAINT MONO (-3940 4060);
FORCEPROP 0 LASTPIN (-3950 4000) $PN CG55
J 0
(-3940 4010);
DISPLAY 0.489362 (-3940 4010);
PAINT MONO (-3940 4010);
FORCEPROP 0 LASTPIN (-3950 3950) $PN CG57
J 0
(-3940 3960);
DISPLAY 0.489362 (-3940 3960);
PAINT MONO (-3940 3960);
FORCEPROP 0 LASTPIN (-3950 3900) $PN CH55
J 0
(-3940 3910);
DISPLAY 0.489362 (-3940 3910);
PAINT MONO (-3940 3910);
FORCEPROP 0 LASTPIN (-3950 3800) $PN CH56
J 0
(-3940 3810);
DISPLAY 0.489362 (-3940 3810);
PAINT MONO (-3940 3810);
FORCEPROP 0 LASTPIN (-3950 3750) $PN CJ55
J 0
(-3940 3760);
DISPLAY 0.489362 (-3940 3760);
PAINT MONO (-3940 3760);
FORCEPROP 0 LASTPIN (-3950 3700) $PN CJ57
J 0
(-3940 3710);
DISPLAY 0.489362 (-3940 3710);
PAINT MONO (-3940 3710);
FORCEPROP 0 LASTPIN (-3950 3650) $PN CK55
J 0
(-3940 3660);
DISPLAY 0.489362 (-3940 3660);
PAINT MONO (-3940 3660);
FORCEPROP 0 LASTPIN (-3950 3600) $PN CM56
J 0
(-3940 3610);
DISPLAY 0.489362 (-3940 3610);
PAINT MONO (-3940 3610);
FORCEPROP 0 LASTPIN (-3950 3550) $PN CN55
J 0
(-3940 3560);
DISPLAY 0.489362 (-3940 3560);
PAINT MONO (-3940 3560);
FORCEPROP 0 LASTPIN (-3950 3500) $PN CN57
J 0
(-3940 3510);
DISPLAY 0.489362 (-3940 3510);
PAINT MONO (-3940 3510);
FORCEPROP 0 LASTPIN (-3950 3450) $PN CP55
J 0
(-3940 3460);
DISPLAY 0.489362 (-3940 3460);
PAINT MONO (-3940 3460);
FORCEPROP 0 LASTPIN (-3950 3350) $PN CP56
J 0
(-3940 3360);
DISPLAY 0.489362 (-3940 3360);
PAINT MONO (-3940 3360);
FORCEPROP 0 LASTPIN (-3950 3300) $PN CR55
J 0
(-3940 3310);
DISPLAY 0.489362 (-3940 3310);
PAINT MONO (-3940 3310);
FORCEPROP 0 LASTPIN (-3950 3250) $PN CR57
J 0
(-3940 3260);
DISPLAY 0.489362 (-3940 3260);
PAINT MONO (-3940 3260);
FORCEPROP 0 LASTPIN (-3950 3200) $PN CT55
J 0
(-3940 3210);
DISPLAY 0.489362 (-3940 3210);
PAINT MONO (-3940 3210);
FORCEPROP 0 LASTPIN (-3950 3150) $PN CV56
J 0
(-3940 3160);
DISPLAY 0.489362 (-3940 3160);
PAINT MONO (-3940 3160);
FORCEPROP 0 LASTPIN (-3950 3100) $PN CW55
J 0
(-3940 3110);
DISPLAY 0.489362 (-3940 3110);
PAINT MONO (-3940 3110);
FORCEPROP 0 LASTPIN (-3950 3050) $PN CW57
J 0
(-3940 3060);
DISPLAY 0.489362 (-3940 3060);
PAINT MONO (-3940 3060);
FORCEPROP 0 LASTPIN (-3950 3000) $PN CY55
J 0
(-3940 3010);
DISPLAY 0.489362 (-3940 3010);
PAINT MONO (-3940 3010);
FORCEPROP 0 LASTPIN (-3950 2900) $PN CY56
J 0
(-3940 2910);
DISPLAY 0.489362 (-3940 2910);
PAINT MONO (-3940 2910);
FORCEPROP 0 LASTPIN (-3950 2850) $PN DA55
J 0
(-3940 2860);
DISPLAY 0.489362 (-3940 2860);
PAINT MONO (-3940 2860);
FORCEPROP 0 LASTPIN (-3950 2800) $PN DA57
J 0
(-3940 2810);
DISPLAY 0.489362 (-3940 2810);
PAINT MONO (-3940 2810);
FORCEPROP 0 LASTPIN (-3950 2750) $PN DB55
J 0
(-3940 2760);
DISPLAY 0.489362 (-3940 2760);
PAINT MONO (-3940 2760);
FORCEPROP 0 LASTPIN (-3950 2700) $PN DD56
J 0
(-3940 2710);
DISPLAY 0.489362 (-3940 2710);
PAINT MONO (-3940 2710);
FORCEPROP 0 LASTPIN (-3950 2650) $PN DE55
J 0
(-3940 2660);
DISPLAY 0.489362 (-3940 2660);
PAINT MONO (-3940 2660);
FORCEPROP 0 LASTPIN (-3950 2600) $PN DE57
J 0
(-3940 2610);
DISPLAY 0.489362 (-3940 2610);
PAINT MONO (-3940 2610);
FORCEPROP 0 LASTPIN (-3950 2550) $PN DF55
J 0
(-3940 2560);
DISPLAY 0.489362 (-3940 2560);
PAINT MONO (-3940 2560);
FORCEPROP 0 LASTPIN (-5550 5000) $PN CD56
J 2
(-5560 5010);
DISPLAY 0.489362 (-5560 5010);
PAINT MONO (-5560 5010);
FORCEPROP 0 LASTPIN (-5550 4900) $PN CK56
J 2
(-5560 4910);
DISPLAY 0.489362 (-5560 4910);
PAINT MONO (-5560 4910);
FORCEPROP 0 LASTPIN (-5550 4800) $PN CT56
J 2
(-5560 4810);
DISPLAY 0.489362 (-5560 4810);
PAINT MONO (-5560 4810);
FORCEPROP 0 LASTPIN (-5550 4700) $PN DB56
J 2
(-5560 4710);
DISPLAY 0.489362 (-5560 4710);
PAINT MONO (-5560 4710);
FORCEPROP 0 LASTPIN (-5550 4600) $PN BY55
J 2
(-5560 4610);
DISPLAY 0.489362 (-5560 4610);
PAINT MONO (-5560 4610);
FORCEPROP 0 LASTPIN (-5550 4500) $PN CF55
J 2
(-5560 4510);
DISPLAY 0.489362 (-5560 4510);
PAINT MONO (-5560 4510);
FORCEPROP 0 LASTPIN (-5550 4400) $PN CM55
J 2
(-5560 4410);
DISPLAY 0.489362 (-5560 4410);
PAINT MONO (-5560 4410);
FORCEPROP 0 LASTPIN (-5550 4300) $PN CV55
J 2
(-5560 4310);
DISPLAY 0.489362 (-5560 4310);
PAINT MONO (-5560 4310);
FORCEPROP 0 LASTPIN (-5550 4200) $PN DD55
J 2
(-5560 4210);
DISPLAY 0.489362 (-5560 4210);
PAINT MONO (-5560 4210);
FORCEPROP 0 LASTPIN (-5550 4100) $PN BV56
J 2
(-5560 4110);
DISPLAY 0.489362 (-5560 4110);
PAINT MONO (-5560 4110);
FORCEPROP 0 LASTPIN (-5550 4950) $PN CE57
J 2
(-5560 4960);
DISPLAY 0.489362 (-5560 4960);
PAINT MONO (-5560 4960);
FORCEPROP 0 LASTPIN (-5550 4850) $PN CL57
J 2
(-5560 4860);
DISPLAY 0.489362 (-5560 4860);
PAINT MONO (-5560 4860);
FORCEPROP 0 LASTPIN (-5550 4750) $PN CU57
J 2
(-5560 4760);
DISPLAY 0.489362 (-5560 4760);
PAINT MONO (-5560 4760);
FORCEPROP 0 LASTPIN (-5550 4650) $PN DC57
J 2
(-5560 4660);
DISPLAY 0.489362 (-5560 4660);
PAINT MONO (-5560 4660);
FORCEPROP 0 LASTPIN (-5550 4550) $PN BW55
J 2
(-5560 4560);
DISPLAY 0.489362 (-5560 4560);
PAINT MONO (-5560 4560);
FORCEPROP 0 LASTPIN (-5550 4450) $PN CE55
J 2
(-5560 4460);
DISPLAY 0.489362 (-5560 4460);
PAINT MONO (-5560 4460);
FORCEPROP 0 LASTPIN (-5550 4350) $PN CL55
J 2
(-5560 4360);
DISPLAY 0.489362 (-5560 4360);
PAINT MONO (-5560 4360);
FORCEPROP 0 LASTPIN (-5550 4250) $PN CU55
J 2
(-5560 4260);
DISPLAY 0.489362 (-5560 4260);
PAINT MONO (-5560 4260);
FORCEPROP 0 LASTPIN (-5550 4150) $PN DC55
J 2
(-5560 4160);
DISPLAY 0.489362 (-5560 4160);
PAINT MONO (-5560 4160);
FORCEPROP 0 LASTPIN (-5550 4050) $PN BW57
J 2
(-5560 4060);
DISPLAY 0.489362 (-5560 4060);
PAINT MONO (-5560 4060);
FORCEPROP 0 LASTPIN (-5550 2300) $PN BL57
J 2
(-5560 2310);
DISPLAY 0.489362 (-5560 2310);
PAINT MONO (-5560 2310);
FORCEPROP 0 LASTPIN (-5550 1250) $PN BF55
J 2
(-5560 1260);
DISPLAY 0.489362 (-5560 1260);
PAINT MONO (-5560 1260);
FORCEPROP 2 LAST PART_TYPE SMLF
J 0
(-5400 6425);
DISPLAY 1.021277 (-5400 6425);
FORCEPROP 1 LAST MATERIAL IO
J 0
(-5395 6232);
DISPLAY 0.489362 (-5395 6232);
PAINT SKYBLUE (-5395 6232);
FORCEPROP 2 LAST VALUE SOCKET6096_13568-001
J 0
(-5400 6325);
DISPLAY 0.489362 (-5400 6325);
PAINT SKYBLUE (-5400 6325);
FORCEPROP 1 LAST PART_NUMBER DGA^6000030
J 0
(-5395 6359);
DISPLAY 0.489362 (-5395 6359);
PAINT SKYBLUE (-5395 6359);
FORCEPROP 2 LAST CDS_LIB pure_quanta
J 0
(-4750 3675);
DISPLAY INVISIBLE (-4750 3675);
FORCEPROP 1 LAST CDS_LMAN_SYM_OUTLINE -650,2525,650,-2525
J 0
(-4750 3675);
DISPLAY 0.468085 (-4750 3675);
PAINT GREEN (-4750 3675);
DISPLAY INVISIBLE (-4750 3675);
FORCEPROP 1 LAST NEEDS_NO_SIZE TRUE
J 0
(-4750 3675);
DISPLAY 0.723404 (-4750 3675);
PAINT GREEN (-4750 3675);
DISPLAY INVISIBLE (-4750 3675);
FORCEPROP 1 LAST PATH I159
J 0
(-4750 3675);
DISPLAY 0.723404 (-4750 3675);
PAINT GREEN (-4750 3675);
DISPLAY INVISIBLE (-4750 3675);
FORCEADD OFFPAGE..3
(-2750 6075);
FORCEPROP 2 LAST $XR0 99 
J 0
(-2536 6075);
DISPLAY 0.638298 (-2536 6075);
PAINT MONO (-2536 6075);
FORCEPROP 2 LAST PATH I160
J 0
(-2525 6125);
DISPLAY 1.021277 (-2525 6125);
DISPLAY INVISIBLE (-2525 6125);
FORCEPROP 1 LAST COMMENT_BODY TRUE
J 0
(-2800 5975);
DISPLAY 0.872340 (-2800 5975);
PAINT GREEN (-2800 5975);
DISPLAY INVISIBLE (-2800 5975);
FORCEPROP 1 LAST OFFPAGE TRUE
J 0
(-2425 5950);
DISPLAY 0.872340 (-2425 5950);
PAINT GREEN (-2425 5950);
DISPLAY INVISIBLE (-2425 5950);
FORCEPROP 2 LAST CDS_LIB mstr_standard
J 0
(-2750 6075);
DISPLAY 0.723404 (-2750 6075);
PAINT MONO (-2750 6075);
DISPLAY INVISIBLE (-2750 6075);
FORCEADD OFFPAGE..3
(-2750 4275);
FORCEPROP 2 LAST $XR0 99 
J 0
(-2536 4275);
DISPLAY 0.638298 (-2536 4275);
PAINT MONO (-2536 4275);
FORCEPROP 2 LAST PATH I161
J 0
(-2525 4325);
DISPLAY 1.021277 (-2525 4325);
DISPLAY INVISIBLE (-2525 4325);
FORCEPROP 1 LAST COMMENT_BODY TRUE
J 0
(-2800 4175);
DISPLAY 0.872340 (-2800 4175);
PAINT GREEN (-2800 4175);
DISPLAY INVISIBLE (-2800 4175);
FORCEPROP 1 LAST OFFPAGE TRUE
J 0
(-2425 4150);
DISPLAY 0.872340 (-2425 4150);
PAINT GREEN (-2425 4150);
DISPLAY INVISIBLE (-2425 4150);
FORCEPROP 2 LAST CDS_LIB mstr_standard
J 0
(-2750 4275);
DISPLAY 0.723404 (-2750 4275);
PAINT MONO (-2750 4275);
DISPLAY INVISIBLE (-2750 4275);
FORCEADD TAP..1
(-3475 6050);
FORCEPROP 3 LASTPIN (-3525 6050) SIG_NAME M_C_CPU1_SA_DQ<0>
J 0
(-3515 6060);
DISPLAY 0.659574 (-3515 6060);
PAINT MONO (-3515 6060);
DISPLAY INVISIBLE (-3515 6060);
FORCEPROP 1 LASTPIN (-3525 6050) BN 0
J 0
(-3537 6058);
DISPLAY 0.489362 (-3537 6058);
PAINT GREEN (-3537 6058);
FORCEPROP 2 LAST CDS_LIB mstr_standard
J 0
(-3475 6050);
DISPLAY 0.723404 (-3475 6050);
PAINT MONO (-3475 6050);
DISPLAY INVISIBLE (-3475 6050);
FORCEPROP 1 LAST BODY_TYPE PLUMBING
J 0
(-3475 6100);
DISPLAY 0.872340 (-3475 6100);
PAINT GREEN (-3475 6100);
DISPLAY INVISIBLE (-3475 6100);
FORCEPROP 1 LAST HDL_TAP TRUE
J 0
(-3150 5925);
DISPLAY 0.872340 (-3150 5925);
DISPLAY INVISIBLE (-3150 5925);
FORCEPROP 1 LAST PATH I162
J 0
(-3477 6050);
DISPLAY 0.872340 (-3477 6050);
PAINT GREEN (-3477 6050);
DISPLAY INVISIBLE (-3477 6050);
FORCEADD TAP..1
(-3475 6000);
FORCEPROP 3 LASTPIN (-3525 6000) SIG_NAME M_C_CPU1_SA_DQ<1>
J 0
(-3515 6010);
DISPLAY 0.659574 (-3515 6010);
PAINT MONO (-3515 6010);
DISPLAY INVISIBLE (-3515 6010);
FORCEPROP 1 LASTPIN (-3525 6000) BN 1
J 0
(-3537 6008);
DISPLAY 0.489362 (-3537 6008);
PAINT GREEN (-3537 6008);
FORCEPROP 2 LAST CDS_LIB mstr_standard
J 0
(-3475 6000);
DISPLAY 0.723404 (-3475 6000);
PAINT MONO (-3475 6000);
DISPLAY INVISIBLE (-3475 6000);
FORCEPROP 1 LAST BODY_TYPE PLUMBING
J 0
(-3475 6050);
DISPLAY 0.872340 (-3475 6050);
PAINT GREEN (-3475 6050);
DISPLAY INVISIBLE (-3475 6050);
FORCEPROP 1 LAST HDL_TAP TRUE
J 0
(-3150 5875);
DISPLAY 0.872340 (-3150 5875);
DISPLAY INVISIBLE (-3150 5875);
FORCEPROP 1 LAST PATH I163
J 0
(-3477 6000);
DISPLAY 0.872340 (-3477 6000);
PAINT GREEN (-3477 6000);
DISPLAY INVISIBLE (-3477 6000);
FORCEADD TAP..1
(-3475 5900);
FORCEPROP 3 LASTPIN (-3525 5900) SIG_NAME M_C_CPU1_SA_DQ<3>
J 0
(-3515 5910);
DISPLAY 0.659574 (-3515 5910);
PAINT MONO (-3515 5910);
DISPLAY INVISIBLE (-3515 5910);
FORCEPROP 1 LASTPIN (-3525 5900) BN 3
J 0
(-3537 5908);
DISPLAY 0.489362 (-3537 5908);
PAINT GREEN (-3537 5908);
FORCEPROP 2 LAST CDS_LIB mstr_standard
J 0
(-3475 5900);
DISPLAY 0.723404 (-3475 5900);
PAINT MONO (-3475 5900);
DISPLAY INVISIBLE (-3475 5900);
FORCEPROP 1 LAST BODY_TYPE PLUMBING
J 0
(-3475 5950);
DISPLAY 0.872340 (-3475 5950);
PAINT GREEN (-3475 5950);
DISPLAY INVISIBLE (-3475 5950);
FORCEPROP 1 LAST HDL_TAP TRUE
J 0
(-3150 5775);
DISPLAY 0.872340 (-3150 5775);
DISPLAY INVISIBLE (-3150 5775);
FORCEPROP 1 LAST PATH I164
J 0
(-3477 5900);
DISPLAY 0.872340 (-3477 5900);
PAINT GREEN (-3477 5900);
DISPLAY INVISIBLE (-3477 5900);
FORCEADD TAP..1
(-3475 5950);
FORCEPROP 3 LASTPIN (-3525 5950) SIG_NAME M_C_CPU1_SA_DQ<2>
J 0
(-3515 5960);
DISPLAY 0.659574 (-3515 5960);
PAINT MONO (-3515 5960);
DISPLAY INVISIBLE (-3515 5960);
FORCEPROP 1 LASTPIN (-3525 5950) BN 2
J 0
(-3537 5958);
DISPLAY 0.489362 (-3537 5958);
PAINT GREEN (-3537 5958);
FORCEPROP 2 LAST CDS_LIB mstr_standard
J 0
(-3475 5950);
DISPLAY 0.723404 (-3475 5950);
PAINT MONO (-3475 5950);
DISPLAY INVISIBLE (-3475 5950);
FORCEPROP 1 LAST BODY_TYPE PLUMBING
J 0
(-3475 6000);
DISPLAY 0.872340 (-3475 6000);
PAINT GREEN (-3475 6000);
DISPLAY INVISIBLE (-3475 6000);
FORCEPROP 1 LAST HDL_TAP TRUE
J 0
(-3150 5825);
DISPLAY 0.872340 (-3150 5825);
DISPLAY INVISIBLE (-3150 5825);
FORCEPROP 1 LAST PATH I165
J 0
(-3477 5950);
DISPLAY 0.872340 (-3477 5950);
PAINT GREEN (-3477 5950);
DISPLAY INVISIBLE (-3477 5950);
FORCEADD TAP..1
(-3475 5750);
FORCEPROP 3 LASTPIN (-3525 5750) SIG_NAME M_C_CPU1_SA_DQ<6>
J 0
(-3515 5760);
DISPLAY 0.659574 (-3515 5760);
PAINT MONO (-3515 5760);
DISPLAY INVISIBLE (-3515 5760);
FORCEPROP 1 LASTPIN (-3525 5750) BN 6
J 0
(-3537 5758);
DISPLAY 0.489362 (-3537 5758);
PAINT GREEN (-3537 5758);
FORCEPROP 2 LAST CDS_LIB mstr_standard
J 0
(-3475 5750);
DISPLAY 0.723404 (-3475 5750);
PAINT MONO (-3475 5750);
DISPLAY INVISIBLE (-3475 5750);
FORCEPROP 1 LAST BODY_TYPE PLUMBING
J 0
(-3475 5800);
DISPLAY 0.872340 (-3475 5800);
PAINT GREEN (-3475 5800);
DISPLAY INVISIBLE (-3475 5800);
FORCEPROP 1 LAST HDL_TAP TRUE
J 0
(-3150 5625);
DISPLAY 0.872340 (-3150 5625);
DISPLAY INVISIBLE (-3150 5625);
FORCEPROP 1 LAST PATH I166
J 0
(-3477 5750);
DISPLAY 0.872340 (-3477 5750);
PAINT GREEN (-3477 5750);
DISPLAY INVISIBLE (-3477 5750);
FORCEADD TAP..1
(-3475 5800);
FORCEPROP 3 LASTPIN (-3525 5800) SIG_NAME M_C_CPU1_SA_DQ<5>
J 0
(-3515 5810);
DISPLAY 0.659574 (-3515 5810);
PAINT MONO (-3515 5810);
DISPLAY INVISIBLE (-3515 5810);
FORCEPROP 1 LASTPIN (-3525 5800) BN 5
J 0
(-3537 5808);
DISPLAY 0.489362 (-3537 5808);
PAINT GREEN (-3537 5808);
FORCEPROP 2 LAST CDS_LIB mstr_standard
J 0
(-3475 5800);
DISPLAY 0.723404 (-3475 5800);
PAINT MONO (-3475 5800);
DISPLAY INVISIBLE (-3475 5800);
FORCEPROP 1 LAST BODY_TYPE PLUMBING
J 0
(-3475 5850);
DISPLAY 0.872340 (-3475 5850);
PAINT GREEN (-3475 5850);
DISPLAY INVISIBLE (-3475 5850);
FORCEPROP 1 LAST HDL_TAP TRUE
J 0
(-3150 5675);
DISPLAY 0.872340 (-3150 5675);
DISPLAY INVISIBLE (-3150 5675);
FORCEPROP 1 LAST PATH I167
J 0
(-3477 5800);
DISPLAY 0.872340 (-3477 5800);
PAINT GREEN (-3477 5800);
DISPLAY INVISIBLE (-3477 5800);
FORCEADD TAP..1
(-3475 5850);
FORCEPROP 3 LASTPIN (-3525 5850) SIG_NAME M_C_CPU1_SA_DQ<4>
J 0
(-3515 5860);
DISPLAY 0.659574 (-3515 5860);
PAINT MONO (-3515 5860);
DISPLAY INVISIBLE (-3515 5860);
FORCEPROP 1 LASTPIN (-3525 5850) BN 4
J 0
(-3537 5858);
DISPLAY 0.489362 (-3537 5858);
PAINT GREEN (-3537 5858);
FORCEPROP 2 LAST CDS_LIB mstr_standard
J 0
(-3475 5850);
DISPLAY 0.723404 (-3475 5850);
PAINT MONO (-3475 5850);
DISPLAY INVISIBLE (-3475 5850);
FORCEPROP 1 LAST BODY_TYPE PLUMBING
J 0
(-3475 5900);
DISPLAY 0.872340 (-3475 5900);
PAINT GREEN (-3475 5900);
DISPLAY INVISIBLE (-3475 5900);
FORCEPROP 1 LAST HDL_TAP TRUE
J 0
(-3150 5725);
DISPLAY 0.872340 (-3150 5725);
DISPLAY INVISIBLE (-3150 5725);
FORCEPROP 1 LAST PATH I168
J 0
(-3477 5850);
DISPLAY 0.872340 (-3477 5850);
PAINT GREEN (-3477 5850);
DISPLAY INVISIBLE (-3477 5850);
FORCEADD TAP..1
(-3475 5700);
FORCEPROP 3 LASTPIN (-3525 5700) SIG_NAME M_C_CPU1_SA_DQ<7>
J 0
(-3515 5710);
DISPLAY 0.659574 (-3515 5710);
PAINT MONO (-3515 5710);
DISPLAY INVISIBLE (-3515 5710);
FORCEPROP 1 LASTPIN (-3525 5700) BN 7
J 0
(-3537 5708);
DISPLAY 0.489362 (-3537 5708);
PAINT GREEN (-3537 5708);
FORCEPROP 2 LAST CDS_LIB mstr_standard
J 0
(-3475 5700);
DISPLAY 0.723404 (-3475 5700);
PAINT MONO (-3475 5700);
DISPLAY INVISIBLE (-3475 5700);
FORCEPROP 1 LAST BODY_TYPE PLUMBING
J 0
(-3475 5750);
DISPLAY 0.872340 (-3475 5750);
PAINT GREEN (-3475 5750);
DISPLAY INVISIBLE (-3475 5750);
FORCEPROP 1 LAST HDL_TAP TRUE
J 0
(-3150 5575);
DISPLAY 0.872340 (-3150 5575);
DISPLAY INVISIBLE (-3150 5575);
FORCEPROP 1 LAST PATH I169
J 0
(-3477 5700);
DISPLAY 0.872340 (-3477 5700);
PAINT GREEN (-3477 5700);
DISPLAY INVISIBLE (-3477 5700);
FORCEADD TAP..1
(-3475 5550);
FORCEPROP 3 LASTPIN (-3525 5550) SIG_NAME M_C_CPU1_SA_DQ<9>
J 0
(-3515 5560);
DISPLAY 0.659574 (-3515 5560);
PAINT MONO (-3515 5560);
DISPLAY INVISIBLE (-3515 5560);
FORCEPROP 1 LASTPIN (-3525 5550) BN 9
J 0
(-3537 5558);
DISPLAY 0.489362 (-3537 5558);
PAINT GREEN (-3537 5558);
FORCEPROP 2 LAST CDS_LIB mstr_standard
J 0
(-3475 5550);
DISPLAY 0.723404 (-3475 5550);
PAINT MONO (-3475 5550);
DISPLAY INVISIBLE (-3475 5550);
FORCEPROP 1 LAST BODY_TYPE PLUMBING
J 0
(-3475 5600);
DISPLAY 0.872340 (-3475 5600);
PAINT GREEN (-3475 5600);
DISPLAY INVISIBLE (-3475 5600);
FORCEPROP 1 LAST HDL_TAP TRUE
J 0
(-3150 5425);
DISPLAY 0.872340 (-3150 5425);
DISPLAY INVISIBLE (-3150 5425);
FORCEPROP 1 LAST PATH I170
J 0
(-3477 5550);
DISPLAY 0.872340 (-3477 5550);
PAINT GREEN (-3477 5550);
DISPLAY INVISIBLE (-3477 5550);
FORCEADD TAP..1
(-3475 5600);
FORCEPROP 3 LASTPIN (-3525 5600) SIG_NAME M_C_CPU1_SA_DQ<8>
J 0
(-3515 5610);
DISPLAY 0.659574 (-3515 5610);
PAINT MONO (-3515 5610);
DISPLAY INVISIBLE (-3515 5610);
FORCEPROP 1 LASTPIN (-3525 5600) BN 8
J 0
(-3537 5608);
DISPLAY 0.489362 (-3537 5608);
PAINT GREEN (-3537 5608);
FORCEPROP 2 LAST CDS_LIB mstr_standard
J 0
(-3475 5600);
DISPLAY 0.723404 (-3475 5600);
PAINT MONO (-3475 5600);
DISPLAY INVISIBLE (-3475 5600);
FORCEPROP 1 LAST BODY_TYPE PLUMBING
J 0
(-3475 5650);
DISPLAY 0.872340 (-3475 5650);
PAINT GREEN (-3475 5650);
DISPLAY INVISIBLE (-3475 5650);
FORCEPROP 1 LAST HDL_TAP TRUE
J 0
(-3150 5475);
DISPLAY 0.872340 (-3150 5475);
DISPLAY INVISIBLE (-3150 5475);
FORCEPROP 1 LAST PATH I171
J 0
(-3477 5600);
DISPLAY 0.872340 (-3477 5600);
PAINT GREEN (-3477 5600);
DISPLAY INVISIBLE (-3477 5600);
FORCEADD TAP..1
(-3475 5500);
FORCEPROP 3 LASTPIN (-3525 5500) SIG_NAME M_C_CPU1_SA_DQ<10>
J 0
(-3515 5510);
DISPLAY 0.659574 (-3515 5510);
PAINT MONO (-3515 5510);
DISPLAY INVISIBLE (-3515 5510);
FORCEPROP 1 LASTPIN (-3525 5500) BN 10
J 0
(-3537 5508);
DISPLAY 0.489362 (-3537 5508);
PAINT GREEN (-3537 5508);
FORCEPROP 2 LAST CDS_LIB mstr_standard
J 0
(-3475 5500);
DISPLAY 0.723404 (-3475 5500);
PAINT MONO (-3475 5500);
DISPLAY INVISIBLE (-3475 5500);
FORCEPROP 1 LAST BODY_TYPE PLUMBING
J 0
(-3475 5550);
DISPLAY 0.872340 (-3475 5550);
PAINT GREEN (-3475 5550);
DISPLAY INVISIBLE (-3475 5550);
FORCEPROP 1 LAST HDL_TAP TRUE
J 0
(-3150 5375);
DISPLAY 0.872340 (-3150 5375);
DISPLAY INVISIBLE (-3150 5375);
FORCEPROP 1 LAST PATH I172
J 0
(-3477 5500);
DISPLAY 0.872340 (-3477 5500);
PAINT GREEN (-3477 5500);
DISPLAY INVISIBLE (-3477 5500);
FORCEADD TAP..1
(-3475 5400);
FORCEPROP 3 LASTPIN (-3525 5400) SIG_NAME M_C_CPU1_SA_DQ<12>
J 0
(-3515 5410);
DISPLAY 0.659574 (-3515 5410);
PAINT MONO (-3515 5410);
DISPLAY INVISIBLE (-3515 5410);
FORCEPROP 1 LASTPIN (-3525 5400) BN 12
J 0
(-3537 5408);
DISPLAY 0.489362 (-3537 5408);
PAINT GREEN (-3537 5408);
FORCEPROP 2 LAST CDS_LIB mstr_standard
J 0
(-3475 5400);
DISPLAY 0.723404 (-3475 5400);
PAINT MONO (-3475 5400);
DISPLAY INVISIBLE (-3475 5400);
FORCEPROP 1 LAST BODY_TYPE PLUMBING
J 0
(-3475 5450);
DISPLAY 0.872340 (-3475 5450);
PAINT GREEN (-3475 5450);
DISPLAY INVISIBLE (-3475 5450);
FORCEPROP 1 LAST HDL_TAP TRUE
J 0
(-3150 5275);
DISPLAY 0.872340 (-3150 5275);
DISPLAY INVISIBLE (-3150 5275);
FORCEPROP 1 LAST PATH I173
J 0
(-3477 5400);
DISPLAY 0.872340 (-3477 5400);
PAINT GREEN (-3477 5400);
DISPLAY INVISIBLE (-3477 5400);
FORCEADD TAP..1
(-3475 5450);
FORCEPROP 3 LASTPIN (-3525 5450) SIG_NAME M_C_CPU1_SA_DQ<11>
J 0
(-3515 5460);
DISPLAY 0.659574 (-3515 5460);
PAINT MONO (-3515 5460);
DISPLAY INVISIBLE (-3515 5460);
FORCEPROP 1 LASTPIN (-3525 5450) BN 11
J 0
(-3537 5458);
DISPLAY 0.489362 (-3537 5458);
PAINT GREEN (-3537 5458);
FORCEPROP 2 LAST CDS_LIB mstr_standard
J 0
(-3475 5450);
DISPLAY 0.723404 (-3475 5450);
PAINT MONO (-3475 5450);
DISPLAY INVISIBLE (-3475 5450);
FORCEPROP 1 LAST BODY_TYPE PLUMBING
J 0
(-3475 5500);
DISPLAY 0.872340 (-3475 5500);
PAINT GREEN (-3475 5500);
DISPLAY INVISIBLE (-3475 5500);
FORCEPROP 1 LAST HDL_TAP TRUE
J 0
(-3150 5325);
DISPLAY 0.872340 (-3150 5325);
DISPLAY INVISIBLE (-3150 5325);
FORCEPROP 1 LAST PATH I174
J 0
(-3477 5450);
DISPLAY 0.872340 (-3477 5450);
PAINT GREEN (-3477 5450);
DISPLAY INVISIBLE (-3477 5450);
FORCEADD TAP..1
(-3475 5350);
FORCEPROP 3 LASTPIN (-3525 5350) SIG_NAME M_C_CPU1_SA_DQ<13>
J 0
(-3515 5360);
DISPLAY 0.659574 (-3515 5360);
PAINT MONO (-3515 5360);
DISPLAY INVISIBLE (-3515 5360);
FORCEPROP 1 LASTPIN (-3525 5350) BN 13
J 0
(-3537 5358);
DISPLAY 0.489362 (-3537 5358);
PAINT GREEN (-3537 5358);
FORCEPROP 2 LAST CDS_LIB mstr_standard
J 0
(-3475 5350);
DISPLAY 0.723404 (-3475 5350);
PAINT MONO (-3475 5350);
DISPLAY INVISIBLE (-3475 5350);
FORCEPROP 1 LAST BODY_TYPE PLUMBING
J 0
(-3475 5400);
DISPLAY 0.872340 (-3475 5400);
PAINT GREEN (-3475 5400);
DISPLAY INVISIBLE (-3475 5400);
FORCEPROP 1 LAST HDL_TAP TRUE
J 0
(-3150 5225);
DISPLAY 0.872340 (-3150 5225);
DISPLAY INVISIBLE (-3150 5225);
FORCEPROP 1 LAST PATH I175
J 0
(-3477 5350);
DISPLAY 0.872340 (-3477 5350);
PAINT GREEN (-3477 5350);
DISPLAY INVISIBLE (-3477 5350);
FORCEADD TAP..1
(-3475 5300);
FORCEPROP 3 LASTPIN (-3525 5300) SIG_NAME M_C_CPU1_SA_DQ<14>
J 0
(-3515 5310);
DISPLAY 0.659574 (-3515 5310);
PAINT MONO (-3515 5310);
DISPLAY INVISIBLE (-3515 5310);
FORCEPROP 1 LASTPIN (-3525 5300) BN 14
J 0
(-3537 5308);
DISPLAY 0.489362 (-3537 5308);
PAINT GREEN (-3537 5308);
FORCEPROP 2 LAST CDS_LIB mstr_standard
J 0
(-3475 5300);
DISPLAY 0.723404 (-3475 5300);
PAINT MONO (-3475 5300);
DISPLAY INVISIBLE (-3475 5300);
FORCEPROP 1 LAST BODY_TYPE PLUMBING
J 0
(-3475 5350);
DISPLAY 0.872340 (-3475 5350);
PAINT GREEN (-3475 5350);
DISPLAY INVISIBLE (-3475 5350);
FORCEPROP 1 LAST HDL_TAP TRUE
J 0
(-3150 5175);
DISPLAY 0.872340 (-3150 5175);
DISPLAY INVISIBLE (-3150 5175);
FORCEPROP 1 LAST PATH I176
J 0
(-3477 5300);
DISPLAY 0.872340 (-3477 5300);
PAINT GREEN (-3477 5300);
DISPLAY INVISIBLE (-3477 5300);
FORCEADD TAP..1
(-3475 5250);
FORCEPROP 3 LASTPIN (-3525 5250) SIG_NAME M_C_CPU1_SA_DQ<15>
J 0
(-3515 5260);
DISPLAY 0.659574 (-3515 5260);
PAINT MONO (-3515 5260);
DISPLAY INVISIBLE (-3515 5260);
FORCEPROP 1 LASTPIN (-3525 5250) BN 15
J 0
(-3537 5258);
DISPLAY 0.489362 (-3537 5258);
PAINT GREEN (-3537 5258);
FORCEPROP 2 LAST CDS_LIB mstr_standard
J 0
(-3475 5250);
DISPLAY 0.723404 (-3475 5250);
PAINT MONO (-3475 5250);
DISPLAY INVISIBLE (-3475 5250);
FORCEPROP 1 LAST BODY_TYPE PLUMBING
J 0
(-3475 5300);
DISPLAY 0.872340 (-3475 5300);
PAINT GREEN (-3475 5300);
DISPLAY INVISIBLE (-3475 5300);
FORCEPROP 1 LAST HDL_TAP TRUE
J 0
(-3150 5125);
DISPLAY 0.872340 (-3150 5125);
DISPLAY INVISIBLE (-3150 5125);
FORCEPROP 1 LAST PATH I177
J 0
(-3477 5250);
DISPLAY 0.872340 (-3477 5250);
PAINT GREEN (-3477 5250);
DISPLAY INVISIBLE (-3477 5250);
FORCEADD TAP..1
(-3475 5150);
FORCEPROP 3 LASTPIN (-3525 5150) SIG_NAME M_C_CPU1_SA_DQ<16>
J 0
(-3515 5160);
DISPLAY 0.659574 (-3515 5160);
PAINT MONO (-3515 5160);
DISPLAY INVISIBLE (-3515 5160);
FORCEPROP 1 LASTPIN (-3525 5150) BN 16
J 0
(-3537 5158);
DISPLAY 0.489362 (-3537 5158);
PAINT GREEN (-3537 5158);
FORCEPROP 2 LAST CDS_LIB mstr_standard
J 0
(-3475 5150);
DISPLAY 0.723404 (-3475 5150);
PAINT MONO (-3475 5150);
DISPLAY INVISIBLE (-3475 5150);
FORCEPROP 1 LAST BODY_TYPE PLUMBING
J 0
(-3475 5200);
DISPLAY 0.872340 (-3475 5200);
PAINT GREEN (-3475 5200);
DISPLAY INVISIBLE (-3475 5200);
FORCEPROP 1 LAST HDL_TAP TRUE
J 0
(-3150 5025);
DISPLAY 0.872340 (-3150 5025);
DISPLAY INVISIBLE (-3150 5025);
FORCEPROP 1 LAST PATH I178
J 0
(-3477 5150);
DISPLAY 0.872340 (-3477 5150);
PAINT GREEN (-3477 5150);
DISPLAY INVISIBLE (-3477 5150);
FORCEADD TAP..1
(-3475 5000);
FORCEPROP 3 LASTPIN (-3525 5000) SIG_NAME M_C_CPU1_SA_DQ<19>
J 0
(-3515 5010);
DISPLAY 0.659574 (-3515 5010);
PAINT MONO (-3515 5010);
DISPLAY INVISIBLE (-3515 5010);
FORCEPROP 1 LASTPIN (-3525 5000) BN 19
J 0
(-3537 5008);
DISPLAY 0.489362 (-3537 5008);
PAINT GREEN (-3537 5008);
FORCEPROP 2 LAST CDS_LIB mstr_standard
J 0
(-3475 5000);
DISPLAY 0.723404 (-3475 5000);
PAINT MONO (-3475 5000);
DISPLAY INVISIBLE (-3475 5000);
FORCEPROP 1 LAST BODY_TYPE PLUMBING
J 0
(-3475 5050);
DISPLAY 0.872340 (-3475 5050);
PAINT GREEN (-3475 5050);
DISPLAY INVISIBLE (-3475 5050);
FORCEPROP 1 LAST HDL_TAP TRUE
J 0
(-3150 4875);
DISPLAY 0.872340 (-3150 4875);
DISPLAY INVISIBLE (-3150 4875);
FORCEPROP 1 LAST PATH I179
J 0
(-3477 5000);
DISPLAY 0.872340 (-3477 5000);
PAINT GREEN (-3477 5000);
DISPLAY INVISIBLE (-3477 5000);
FORCEADD TAP..1
(-3475 5050);
FORCEPROP 3 LASTPIN (-3525 5050) SIG_NAME M_C_CPU1_SA_DQ<18>
J 0
(-3515 5060);
DISPLAY 0.659574 (-3515 5060);
PAINT MONO (-3515 5060);
DISPLAY INVISIBLE (-3515 5060);
FORCEPROP 1 LASTPIN (-3525 5050) BN 18
J 0
(-3537 5058);
DISPLAY 0.489362 (-3537 5058);
PAINT GREEN (-3537 5058);
FORCEPROP 2 LAST CDS_LIB mstr_standard
J 0
(-3475 5050);
DISPLAY 0.723404 (-3475 5050);
PAINT MONO (-3475 5050);
DISPLAY INVISIBLE (-3475 5050);
FORCEPROP 1 LAST BODY_TYPE PLUMBING
J 0
(-3475 5100);
DISPLAY 0.872340 (-3475 5100);
PAINT GREEN (-3475 5100);
DISPLAY INVISIBLE (-3475 5100);
FORCEPROP 1 LAST HDL_TAP TRUE
J 0
(-3150 4925);
DISPLAY 0.872340 (-3150 4925);
DISPLAY INVISIBLE (-3150 4925);
FORCEPROP 1 LAST PATH I180
J 0
(-3477 5050);
DISPLAY 0.872340 (-3477 5050);
PAINT GREEN (-3477 5050);
DISPLAY INVISIBLE (-3477 5050);
FORCEADD TAP..1
(-3475 5100);
FORCEPROP 3 LASTPIN (-3525 5100) SIG_NAME M_C_CPU1_SA_DQ<17>
J 0
(-3515 5110);
DISPLAY 0.659574 (-3515 5110);
PAINT MONO (-3515 5110);
DISPLAY INVISIBLE (-3515 5110);
FORCEPROP 1 LASTPIN (-3525 5100) BN 17
J 0
(-3537 5108);
DISPLAY 0.489362 (-3537 5108);
PAINT GREEN (-3537 5108);
FORCEPROP 2 LAST CDS_LIB mstr_standard
J 0
(-3475 5100);
DISPLAY 0.723404 (-3475 5100);
PAINT MONO (-3475 5100);
DISPLAY INVISIBLE (-3475 5100);
FORCEPROP 1 LAST BODY_TYPE PLUMBING
J 0
(-3475 5150);
DISPLAY 0.872340 (-3475 5150);
PAINT GREEN (-3475 5150);
DISPLAY INVISIBLE (-3475 5150);
FORCEPROP 1 LAST HDL_TAP TRUE
J 0
(-3150 4975);
DISPLAY 0.872340 (-3150 4975);
DISPLAY INVISIBLE (-3150 4975);
FORCEPROP 1 LAST PATH I181
J 0
(-3477 5100);
DISPLAY 0.872340 (-3477 5100);
PAINT GREEN (-3477 5100);
DISPLAY INVISIBLE (-3477 5100);
FORCEADD TAP..1
(-3475 4900);
FORCEPROP 3 LASTPIN (-3525 4900) SIG_NAME M_C_CPU1_SA_DQ<21>
J 0
(-3515 4910);
DISPLAY 0.659574 (-3515 4910);
PAINT MONO (-3515 4910);
DISPLAY INVISIBLE (-3515 4910);
FORCEPROP 1 LASTPIN (-3525 4900) BN 21
J 0
(-3537 4908);
DISPLAY 0.489362 (-3537 4908);
PAINT GREEN (-3537 4908);
FORCEPROP 2 LAST CDS_LIB mstr_standard
J 0
(-3475 4900);
DISPLAY 0.723404 (-3475 4900);
PAINT MONO (-3475 4900);
DISPLAY INVISIBLE (-3475 4900);
FORCEPROP 1 LAST BODY_TYPE PLUMBING
J 0
(-3475 4950);
DISPLAY 0.872340 (-3475 4950);
PAINT GREEN (-3475 4950);
DISPLAY INVISIBLE (-3475 4950);
FORCEPROP 1 LAST HDL_TAP TRUE
J 0
(-3150 4775);
DISPLAY 0.872340 (-3150 4775);
DISPLAY INVISIBLE (-3150 4775);
FORCEPROP 1 LAST PATH I182
J 0
(-3477 4900);
DISPLAY 0.872340 (-3477 4900);
PAINT GREEN (-3477 4900);
DISPLAY INVISIBLE (-3477 4900);
FORCEADD TAP..1
(-3475 4950);
FORCEPROP 3 LASTPIN (-3525 4950) SIG_NAME M_C_CPU1_SA_DQ<20>
J 0
(-3515 4960);
DISPLAY 0.659574 (-3515 4960);
PAINT MONO (-3515 4960);
DISPLAY INVISIBLE (-3515 4960);
FORCEPROP 1 LASTPIN (-3525 4950) BN 20
J 0
(-3537 4958);
DISPLAY 0.489362 (-3537 4958);
PAINT GREEN (-3537 4958);
FORCEPROP 2 LAST CDS_LIB mstr_standard
J 0
(-3475 4950);
DISPLAY 0.723404 (-3475 4950);
PAINT MONO (-3475 4950);
DISPLAY INVISIBLE (-3475 4950);
FORCEPROP 1 LAST BODY_TYPE PLUMBING
J 0
(-3475 5000);
DISPLAY 0.872340 (-3475 5000);
PAINT GREEN (-3475 5000);
DISPLAY INVISIBLE (-3475 5000);
FORCEPROP 1 LAST HDL_TAP TRUE
J 0
(-3150 4825);
DISPLAY 0.872340 (-3150 4825);
DISPLAY INVISIBLE (-3150 4825);
FORCEPROP 1 LAST PATH I183
J 0
(-3477 4950);
DISPLAY 0.872340 (-3477 4950);
PAINT GREEN (-3477 4950);
DISPLAY INVISIBLE (-3477 4950);
FORCEADD TAP..1
(-3475 4800);
FORCEPROP 3 LASTPIN (-3525 4800) SIG_NAME M_C_CPU1_SA_DQ<23>
J 0
(-3515 4810);
DISPLAY 0.659574 (-3515 4810);
PAINT MONO (-3515 4810);
DISPLAY INVISIBLE (-3515 4810);
FORCEPROP 1 LASTPIN (-3525 4800) BN 23
J 0
(-3537 4808);
DISPLAY 0.489362 (-3537 4808);
PAINT GREEN (-3537 4808);
FORCEPROP 2 LAST CDS_LIB mstr_standard
J 0
(-3475 4800);
DISPLAY 0.723404 (-3475 4800);
PAINT MONO (-3475 4800);
DISPLAY INVISIBLE (-3475 4800);
FORCEPROP 1 LAST BODY_TYPE PLUMBING
J 0
(-3475 4850);
DISPLAY 0.872340 (-3475 4850);
PAINT GREEN (-3475 4850);
DISPLAY INVISIBLE (-3475 4850);
FORCEPROP 1 LAST HDL_TAP TRUE
J 0
(-3150 4675);
DISPLAY 0.872340 (-3150 4675);
DISPLAY INVISIBLE (-3150 4675);
FORCEPROP 1 LAST PATH I184
J 0
(-3477 4800);
DISPLAY 0.872340 (-3477 4800);
PAINT GREEN (-3477 4800);
DISPLAY INVISIBLE (-3477 4800);
FORCEADD TAP..1
(-3475 4850);
FORCEPROP 3 LASTPIN (-3525 4850) SIG_NAME M_C_CPU1_SA_DQ<22>
J 0
(-3515 4860);
DISPLAY 0.659574 (-3515 4860);
PAINT MONO (-3515 4860);
DISPLAY INVISIBLE (-3515 4860);
FORCEPROP 1 LASTPIN (-3525 4850) BN 22
J 0
(-3537 4858);
DISPLAY 0.489362 (-3537 4858);
PAINT GREEN (-3537 4858);
FORCEPROP 2 LAST CDS_LIB mstr_standard
J 0
(-3475 4850);
DISPLAY 0.723404 (-3475 4850);
PAINT MONO (-3475 4850);
DISPLAY INVISIBLE (-3475 4850);
FORCEPROP 1 LAST BODY_TYPE PLUMBING
J 0
(-3475 4900);
DISPLAY 0.872340 (-3475 4900);
PAINT GREEN (-3475 4900);
DISPLAY INVISIBLE (-3475 4900);
FORCEPROP 1 LAST HDL_TAP TRUE
J 0
(-3150 4725);
DISPLAY 0.872340 (-3150 4725);
DISPLAY INVISIBLE (-3150 4725);
FORCEPROP 1 LAST PATH I185
J 0
(-3477 4850);
DISPLAY 0.872340 (-3477 4850);
PAINT GREEN (-3477 4850);
DISPLAY INVISIBLE (-3477 4850);
FORCEADD TAP..1
(-3475 4650);
FORCEPROP 3 LASTPIN (-3525 4650) SIG_NAME M_C_CPU1_SA_DQ<25>
J 0
(-3515 4660);
DISPLAY 0.659574 (-3515 4660);
PAINT MONO (-3515 4660);
DISPLAY INVISIBLE (-3515 4660);
FORCEPROP 1 LASTPIN (-3525 4650) BN 25
J 0
(-3537 4658);
DISPLAY 0.489362 (-3537 4658);
PAINT GREEN (-3537 4658);
FORCEPROP 2 LAST CDS_LIB mstr_standard
J 0
(-3475 4650);
DISPLAY 0.723404 (-3475 4650);
PAINT MONO (-3475 4650);
DISPLAY INVISIBLE (-3475 4650);
FORCEPROP 1 LAST BODY_TYPE PLUMBING
J 0
(-3475 4700);
DISPLAY 0.872340 (-3475 4700);
PAINT GREEN (-3475 4700);
DISPLAY INVISIBLE (-3475 4700);
FORCEPROP 1 LAST HDL_TAP TRUE
J 0
(-3150 4525);
DISPLAY 0.872340 (-3150 4525);
DISPLAY INVISIBLE (-3150 4525);
FORCEPROP 1 LAST PATH I186
J 0
(-3477 4650);
DISPLAY 0.872340 (-3477 4650);
PAINT GREEN (-3477 4650);
DISPLAY INVISIBLE (-3477 4650);
FORCEADD TAP..1
(-3475 4700);
FORCEPROP 3 LASTPIN (-3525 4700) SIG_NAME M_C_CPU1_SA_DQ<24>
J 0
(-3515 4710);
DISPLAY 0.659574 (-3515 4710);
PAINT MONO (-3515 4710);
DISPLAY INVISIBLE (-3515 4710);
FORCEPROP 1 LASTPIN (-3525 4700) BN 24
J 0
(-3537 4708);
DISPLAY 0.489362 (-3537 4708);
PAINT GREEN (-3537 4708);
FORCEPROP 2 LAST CDS_LIB mstr_standard
J 0
(-3475 4700);
DISPLAY 0.723404 (-3475 4700);
PAINT MONO (-3475 4700);
DISPLAY INVISIBLE (-3475 4700);
FORCEPROP 1 LAST BODY_TYPE PLUMBING
J 0
(-3475 4750);
DISPLAY 0.872340 (-3475 4750);
PAINT GREEN (-3475 4750);
DISPLAY INVISIBLE (-3475 4750);
FORCEPROP 1 LAST HDL_TAP TRUE
J 0
(-3150 4575);
DISPLAY 0.872340 (-3150 4575);
DISPLAY INVISIBLE (-3150 4575);
FORCEPROP 1 LAST PATH I187
J 0
(-3477 4700);
DISPLAY 0.872340 (-3477 4700);
PAINT GREEN (-3477 4700);
DISPLAY INVISIBLE (-3477 4700);
FORCEADD TAP..1
(-3475 4600);
FORCEPROP 3 LASTPIN (-3525 4600) SIG_NAME M_C_CPU1_SA_DQ<26>
J 0
(-3515 4610);
DISPLAY 0.659574 (-3515 4610);
PAINT MONO (-3515 4610);
DISPLAY INVISIBLE (-3515 4610);
FORCEPROP 1 LASTPIN (-3525 4600) BN 26
J 0
(-3537 4608);
DISPLAY 0.489362 (-3537 4608);
PAINT GREEN (-3537 4608);
FORCEPROP 2 LAST CDS_LIB mstr_standard
J 0
(-3475 4600);
DISPLAY 0.723404 (-3475 4600);
PAINT MONO (-3475 4600);
DISPLAY INVISIBLE (-3475 4600);
FORCEPROP 1 LAST BODY_TYPE PLUMBING
J 0
(-3475 4650);
DISPLAY 0.872340 (-3475 4650);
PAINT GREEN (-3475 4650);
DISPLAY INVISIBLE (-3475 4650);
FORCEPROP 1 LAST HDL_TAP TRUE
J 0
(-3150 4475);
DISPLAY 0.872340 (-3150 4475);
DISPLAY INVISIBLE (-3150 4475);
FORCEPROP 1 LAST PATH I188
J 0
(-3477 4600);
DISPLAY 0.872340 (-3477 4600);
PAINT GREEN (-3477 4600);
DISPLAY INVISIBLE (-3477 4600);
FORCEADD TAP..1
(-3475 4500);
FORCEPROP 3 LASTPIN (-3525 4500) SIG_NAME M_C_CPU1_SA_DQ<28>
J 0
(-3515 4510);
DISPLAY 0.659574 (-3515 4510);
PAINT MONO (-3515 4510);
DISPLAY INVISIBLE (-3515 4510);
FORCEPROP 1 LASTPIN (-3525 4500) BN 28
J 0
(-3537 4508);
DISPLAY 0.489362 (-3537 4508);
PAINT GREEN (-3537 4508);
FORCEPROP 2 LAST CDS_LIB mstr_standard
J 0
(-3475 4500);
DISPLAY 0.723404 (-3475 4500);
PAINT MONO (-3475 4500);
DISPLAY INVISIBLE (-3475 4500);
FORCEPROP 1 LAST BODY_TYPE PLUMBING
J 0
(-3475 4550);
DISPLAY 0.872340 (-3475 4550);
PAINT GREEN (-3475 4550);
DISPLAY INVISIBLE (-3475 4550);
FORCEPROP 1 LAST HDL_TAP TRUE
J 0
(-3150 4375);
DISPLAY 0.872340 (-3150 4375);
DISPLAY INVISIBLE (-3150 4375);
FORCEPROP 1 LAST PATH I189
J 0
(-3477 4500);
DISPLAY 0.872340 (-3477 4500);
PAINT GREEN (-3477 4500);
DISPLAY INVISIBLE (-3477 4500);
FORCEADD TAP..1
(-3475 4550);
FORCEPROP 3 LASTPIN (-3525 4550) SIG_NAME M_C_CPU1_SA_DQ<27>
J 0
(-3515 4560);
DISPLAY 0.659574 (-3515 4560);
PAINT MONO (-3515 4560);
DISPLAY INVISIBLE (-3515 4560);
FORCEPROP 1 LASTPIN (-3525 4550) BN 27
J 0
(-3537 4558);
DISPLAY 0.489362 (-3537 4558);
PAINT GREEN (-3537 4558);
FORCEPROP 2 LAST CDS_LIB mstr_standard
J 0
(-3475 4550);
DISPLAY 0.723404 (-3475 4550);
PAINT MONO (-3475 4550);
DISPLAY INVISIBLE (-3475 4550);
FORCEPROP 1 LAST BODY_TYPE PLUMBING
J 0
(-3475 4600);
DISPLAY 0.872340 (-3475 4600);
PAINT GREEN (-3475 4600);
DISPLAY INVISIBLE (-3475 4600);
FORCEPROP 1 LAST HDL_TAP TRUE
J 0
(-3150 4425);
DISPLAY 0.872340 (-3150 4425);
DISPLAY INVISIBLE (-3150 4425);
FORCEPROP 1 LAST PATH I190
J 0
(-3477 4550);
DISPLAY 0.872340 (-3477 4550);
PAINT GREEN (-3477 4550);
DISPLAY INVISIBLE (-3477 4550);
FORCEADD TAP..1
(-3475 4400);
FORCEPROP 3 LASTPIN (-3525 4400) SIG_NAME M_C_CPU1_SA_DQ<30>
J 0
(-3515 4410);
DISPLAY 0.659574 (-3515 4410);
PAINT MONO (-3515 4410);
DISPLAY INVISIBLE (-3515 4410);
FORCEPROP 1 LASTPIN (-3525 4400) BN 30
J 0
(-3537 4408);
DISPLAY 0.489362 (-3537 4408);
PAINT GREEN (-3537 4408);
FORCEPROP 2 LAST CDS_LIB mstr_standard
J 0
(-3475 4400);
DISPLAY 0.723404 (-3475 4400);
PAINT MONO (-3475 4400);
DISPLAY INVISIBLE (-3475 4400);
FORCEPROP 1 LAST BODY_TYPE PLUMBING
J 0
(-3475 4450);
DISPLAY 0.872340 (-3475 4450);
PAINT GREEN (-3475 4450);
DISPLAY INVISIBLE (-3475 4450);
FORCEPROP 1 LAST HDL_TAP TRUE
J 0
(-3150 4275);
DISPLAY 0.872340 (-3150 4275);
DISPLAY INVISIBLE (-3150 4275);
FORCEPROP 1 LAST PATH I191
J 0
(-3477 4400);
DISPLAY 0.872340 (-3477 4400);
PAINT GREEN (-3477 4400);
DISPLAY INVISIBLE (-3477 4400);
FORCEADD TAP..1
(-3475 4450);
FORCEPROP 3 LASTPIN (-3525 4450) SIG_NAME M_C_CPU1_SA_DQ<29>
J 0
(-3515 4460);
DISPLAY 0.659574 (-3515 4460);
PAINT MONO (-3515 4460);
DISPLAY INVISIBLE (-3515 4460);
FORCEPROP 1 LASTPIN (-3525 4450) BN 29
J 0
(-3537 4458);
DISPLAY 0.489362 (-3537 4458);
PAINT GREEN (-3537 4458);
FORCEPROP 2 LAST CDS_LIB mstr_standard
J 0
(-3475 4450);
DISPLAY 0.723404 (-3475 4450);
PAINT MONO (-3475 4450);
DISPLAY INVISIBLE (-3475 4450);
FORCEPROP 1 LAST BODY_TYPE PLUMBING
J 0
(-3475 4500);
DISPLAY 0.872340 (-3475 4500);
PAINT GREEN (-3475 4500);
DISPLAY INVISIBLE (-3475 4500);
FORCEPROP 1 LAST HDL_TAP TRUE
J 0
(-3150 4325);
DISPLAY 0.872340 (-3150 4325);
DISPLAY INVISIBLE (-3150 4325);
FORCEPROP 1 LAST PATH I192
J 0
(-3477 4450);
DISPLAY 0.872340 (-3477 4450);
PAINT GREEN (-3477 4450);
DISPLAY INVISIBLE (-3477 4450);
FORCEADD TAP..1
(-3475 4350);
FORCEPROP 3 LASTPIN (-3525 4350) SIG_NAME M_C_CPU1_SA_DQ<31>
J 0
(-3515 4360);
DISPLAY 0.659574 (-3515 4360);
PAINT MONO (-3515 4360);
DISPLAY INVISIBLE (-3515 4360);
FORCEPROP 1 LASTPIN (-3525 4350) BN 31
J 0
(-3537 4358);
DISPLAY 0.489362 (-3537 4358);
PAINT GREEN (-3537 4358);
FORCEPROP 2 LAST CDS_LIB mstr_standard
J 0
(-3475 4350);
DISPLAY 0.723404 (-3475 4350);
PAINT MONO (-3475 4350);
DISPLAY INVISIBLE (-3475 4350);
FORCEPROP 1 LAST BODY_TYPE PLUMBING
J 0
(-3475 4400);
DISPLAY 0.872340 (-3475 4400);
PAINT GREEN (-3475 4400);
DISPLAY INVISIBLE (-3475 4400);
FORCEPROP 1 LAST HDL_TAP TRUE
J 0
(-3150 4225);
DISPLAY 0.872340 (-3150 4225);
DISPLAY INVISIBLE (-3150 4225);
FORCEPROP 1 LAST PATH I193
J 0
(-3477 4350);
DISPLAY 0.872340 (-3477 4350);
PAINT GREEN (-3477 4350);
DISPLAY INVISIBLE (-3477 4350);
FORCEADD TAP..1
(-3475 4250);
FORCEPROP 3 LASTPIN (-3525 4250) SIG_NAME M_C_CPU1_SB_DQ<0>
J 0
(-3515 4260);
DISPLAY 0.659574 (-3515 4260);
PAINT MONO (-3515 4260);
DISPLAY INVISIBLE (-3515 4260);
FORCEPROP 1 LASTPIN (-3525 4250) BN 0
J 0
(-3537 4258);
DISPLAY 0.489362 (-3537 4258);
PAINT GREEN (-3537 4258);
FORCEPROP 2 LAST CDS_LIB mstr_standard
J 0
(-3475 4250);
DISPLAY 0.723404 (-3475 4250);
PAINT MONO (-3475 4250);
DISPLAY INVISIBLE (-3475 4250);
FORCEPROP 1 LAST BODY_TYPE PLUMBING
J 0
(-3475 4300);
DISPLAY 0.872340 (-3475 4300);
PAINT GREEN (-3475 4300);
DISPLAY INVISIBLE (-3475 4300);
FORCEPROP 1 LAST HDL_TAP TRUE
J 0
(-3150 4125);
DISPLAY 0.872340 (-3150 4125);
DISPLAY INVISIBLE (-3150 4125);
FORCEPROP 1 LAST PATH I194
J 0
(-3477 4250);
DISPLAY 0.872340 (-3477 4250);
PAINT GREEN (-3477 4250);
DISPLAY INVISIBLE (-3477 4250);
FORCEADD TAP..1
(-3475 4200);
FORCEPROP 3 LASTPIN (-3525 4200) SIG_NAME M_C_CPU1_SB_DQ<1>
J 0
(-3515 4210);
DISPLAY 0.659574 (-3515 4210);
PAINT MONO (-3515 4210);
DISPLAY INVISIBLE (-3515 4210);
FORCEPROP 1 LASTPIN (-3525 4200) BN 1
J 0
(-3537 4208);
DISPLAY 0.489362 (-3537 4208);
PAINT GREEN (-3537 4208);
FORCEPROP 2 LAST CDS_LIB mstr_standard
J 0
(-3475 4200);
DISPLAY 0.723404 (-3475 4200);
PAINT MONO (-3475 4200);
DISPLAY INVISIBLE (-3475 4200);
FORCEPROP 1 LAST BODY_TYPE PLUMBING
J 0
(-3475 4250);
DISPLAY 0.872340 (-3475 4250);
PAINT GREEN (-3475 4250);
DISPLAY INVISIBLE (-3475 4250);
FORCEPROP 1 LAST HDL_TAP TRUE
J 0
(-3150 4075);
DISPLAY 0.872340 (-3150 4075);
DISPLAY INVISIBLE (-3150 4075);
FORCEPROP 1 LAST PATH I195
J 0
(-3477 4200);
DISPLAY 0.872340 (-3477 4200);
PAINT GREEN (-3477 4200);
DISPLAY INVISIBLE (-3477 4200);
FORCEADD TAP..1
(-3475 4100);
FORCEPROP 3 LASTPIN (-3525 4100) SIG_NAME M_C_CPU1_SB_DQ<3>
J 0
(-3515 4110);
DISPLAY 0.659574 (-3515 4110);
PAINT MONO (-3515 4110);
DISPLAY INVISIBLE (-3515 4110);
FORCEPROP 1 LASTPIN (-3525 4100) BN 3
J 0
(-3537 4108);
DISPLAY 0.489362 (-3537 4108);
PAINT GREEN (-3537 4108);
FORCEPROP 2 LAST CDS_LIB mstr_standard
J 0
(-3475 4100);
DISPLAY 0.723404 (-3475 4100);
PAINT MONO (-3475 4100);
DISPLAY INVISIBLE (-3475 4100);
FORCEPROP 1 LAST BODY_TYPE PLUMBING
J 0
(-3475 4150);
DISPLAY 0.872340 (-3475 4150);
PAINT GREEN (-3475 4150);
DISPLAY INVISIBLE (-3475 4150);
FORCEPROP 1 LAST HDL_TAP TRUE
J 0
(-3150 3975);
DISPLAY 0.872340 (-3150 3975);
DISPLAY INVISIBLE (-3150 3975);
FORCEPROP 1 LAST PATH I196
J 0
(-3477 4100);
DISPLAY 0.872340 (-3477 4100);
PAINT GREEN (-3477 4100);
DISPLAY INVISIBLE (-3477 4100);
FORCEADD TAP..1
(-3475 4150);
FORCEPROP 3 LASTPIN (-3525 4150) SIG_NAME M_C_CPU1_SB_DQ<2>
J 0
(-3515 4160);
DISPLAY 0.659574 (-3515 4160);
PAINT MONO (-3515 4160);
DISPLAY INVISIBLE (-3515 4160);
FORCEPROP 1 LASTPIN (-3525 4150) BN 2
J 0
(-3537 4158);
DISPLAY 0.489362 (-3537 4158);
PAINT GREEN (-3537 4158);
FORCEPROP 2 LAST CDS_LIB mstr_standard
J 0
(-3475 4150);
DISPLAY 0.723404 (-3475 4150);
PAINT MONO (-3475 4150);
DISPLAY INVISIBLE (-3475 4150);
FORCEPROP 1 LAST BODY_TYPE PLUMBING
J 0
(-3475 4200);
DISPLAY 0.872340 (-3475 4200);
PAINT GREEN (-3475 4200);
DISPLAY INVISIBLE (-3475 4200);
FORCEPROP 1 LAST HDL_TAP TRUE
J 0
(-3150 4025);
DISPLAY 0.872340 (-3150 4025);
DISPLAY INVISIBLE (-3150 4025);
FORCEPROP 1 LAST PATH I197
J 0
(-3477 4150);
DISPLAY 0.872340 (-3477 4150);
PAINT GREEN (-3477 4150);
DISPLAY INVISIBLE (-3477 4150);
FORCEADD OFFPAGE..6
R 2
(-2875 2500);
FORCEPROP 2 LAST $XR0 99 
J 0
(-2661 2500);
DISPLAY 0.638298 (-2661 2500);
PAINT MONO (-2661 2500);
FORCEPROP 2 LAST PATH I198
J 0
(-2650 2550);
DISPLAY 1.021277 (-2650 2550);
DISPLAY INVISIBLE (-2650 2550);
FORCEPROP 1 LAST COMMENT_BODY TRUE
J 2
(-2975 2425);
DISPLAY 0.872340 (-2975 2425);
PAINT GREEN (-2975 2425);
DISPLAY INVISIBLE (-2975 2425);
FORCEPROP 1 LAST OFFPAGE TRUE
J 2
(-3200 2375);
DISPLAY 0.872340 (-3200 2375);
PAINT GREEN (-3200 2375);
DISPLAY INVISIBLE (-3200 2375);
FORCEPROP 2 LAST CDS_LIB mstr_standard
J 2
(-2875 2500);
DISPLAY 0.723404 (-2875 2500);
PAINT MONO (-2875 2500);
DISPLAY INVISIBLE (-2875 2500);
FORCEADD TAP..1
(-3475 3950);
FORCEPROP 3 LASTPIN (-3525 3950) SIG_NAME M_C_CPU1_SB_DQ<6>
J 0
(-3515 3960);
DISPLAY 0.659574 (-3515 3960);
PAINT MONO (-3515 3960);
DISPLAY INVISIBLE (-3515 3960);
FORCEPROP 1 LASTPIN (-3525 3950) BN 6
J 0
(-3537 3958);
DISPLAY 0.489362 (-3537 3958);
PAINT GREEN (-3537 3958);
FORCEPROP 2 LAST CDS_LIB mstr_standard
J 0
(-3475 3950);
DISPLAY 0.723404 (-3475 3950);
PAINT MONO (-3475 3950);
DISPLAY INVISIBLE (-3475 3950);
FORCEPROP 1 LAST BODY_TYPE PLUMBING
J 0
(-3475 4000);
DISPLAY 0.872340 (-3475 4000);
PAINT GREEN (-3475 4000);
DISPLAY INVISIBLE (-3475 4000);
FORCEPROP 1 LAST HDL_TAP TRUE
J 0
(-3150 3825);
DISPLAY 0.872340 (-3150 3825);
DISPLAY INVISIBLE (-3150 3825);
FORCEPROP 1 LAST PATH I199
J 0
(-3477 3950);
DISPLAY 0.872340 (-3477 3950);
PAINT GREEN (-3477 3950);
DISPLAY INVISIBLE (-3477 3950);
FORCEADD TAP..1
(-3475 4000);
FORCEPROP 3 LASTPIN (-3525 4000) SIG_NAME M_C_CPU1_SB_DQ<5>
J 0
(-3515 4010);
DISPLAY 0.659574 (-3515 4010);
PAINT MONO (-3515 4010);
DISPLAY INVISIBLE (-3515 4010);
FORCEPROP 1 LASTPIN (-3525 4000) BN 5
J 0
(-3537 4008);
DISPLAY 0.489362 (-3537 4008);
PAINT GREEN (-3537 4008);
FORCEPROP 2 LAST CDS_LIB mstr_standard
J 0
(-3475 4000);
DISPLAY 0.723404 (-3475 4000);
PAINT MONO (-3475 4000);
DISPLAY INVISIBLE (-3475 4000);
FORCEPROP 1 LAST BODY_TYPE PLUMBING
J 0
(-3475 4050);
DISPLAY 0.872340 (-3475 4050);
PAINT GREEN (-3475 4050);
DISPLAY INVISIBLE (-3475 4050);
FORCEPROP 1 LAST HDL_TAP TRUE
J 0
(-3150 3875);
DISPLAY 0.872340 (-3150 3875);
DISPLAY INVISIBLE (-3150 3875);
FORCEPROP 1 LAST PATH I200
J 0
(-3477 4000);
DISPLAY 0.872340 (-3477 4000);
PAINT GREEN (-3477 4000);
DISPLAY INVISIBLE (-3477 4000);
FORCEADD TAP..1
(-3475 4050);
FORCEPROP 3 LASTPIN (-3525 4050) SIG_NAME M_C_CPU1_SB_DQ<4>
J 0
(-3515 4060);
DISPLAY 0.659574 (-3515 4060);
PAINT MONO (-3515 4060);
DISPLAY INVISIBLE (-3515 4060);
FORCEPROP 1 LASTPIN (-3525 4050) BN 4
J 0
(-3537 4058);
DISPLAY 0.489362 (-3537 4058);
PAINT GREEN (-3537 4058);
FORCEPROP 2 LAST CDS_LIB mstr_standard
J 0
(-3475 4050);
DISPLAY 0.723404 (-3475 4050);
PAINT MONO (-3475 4050);
DISPLAY INVISIBLE (-3475 4050);
FORCEPROP 1 LAST BODY_TYPE PLUMBING
J 0
(-3475 4100);
DISPLAY 0.872340 (-3475 4100);
PAINT GREEN (-3475 4100);
DISPLAY INVISIBLE (-3475 4100);
FORCEPROP 1 LAST HDL_TAP TRUE
J 0
(-3150 3925);
DISPLAY 0.872340 (-3150 3925);
DISPLAY INVISIBLE (-3150 3925);
FORCEPROP 1 LAST PATH I201
J 0
(-3477 4050);
DISPLAY 0.872340 (-3477 4050);
PAINT GREEN (-3477 4050);
DISPLAY INVISIBLE (-3477 4050);
FORCEADD TAP..1
(-3475 3900);
FORCEPROP 3 LASTPIN (-3525 3900) SIG_NAME M_C_CPU1_SB_DQ<7>
J 0
(-3515 3910);
DISPLAY 0.659574 (-3515 3910);
PAINT MONO (-3515 3910);
DISPLAY INVISIBLE (-3515 3910);
FORCEPROP 1 LASTPIN (-3525 3900) BN 7
J 0
(-3537 3908);
DISPLAY 0.489362 (-3537 3908);
PAINT GREEN (-3537 3908);
FORCEPROP 2 LAST CDS_LIB mstr_standard
J 0
(-3475 3900);
DISPLAY 0.723404 (-3475 3900);
PAINT MONO (-3475 3900);
DISPLAY INVISIBLE (-3475 3900);
FORCEPROP 1 LAST BODY_TYPE PLUMBING
J 0
(-3475 3950);
DISPLAY 0.872340 (-3475 3950);
PAINT GREEN (-3475 3950);
DISPLAY INVISIBLE (-3475 3950);
FORCEPROP 1 LAST HDL_TAP TRUE
J 0
(-3150 3775);
DISPLAY 0.872340 (-3150 3775);
DISPLAY INVISIBLE (-3150 3775);
FORCEPROP 1 LAST PATH I202
J 0
(-3477 3900);
DISPLAY 0.872340 (-3477 3900);
PAINT GREEN (-3477 3900);
DISPLAY INVISIBLE (-3477 3900);
FORCEADD TAP..1
(-3475 3750);
FORCEPROP 3 LASTPIN (-3525 3750) SIG_NAME M_C_CPU1_SB_DQ<9>
J 0
(-3515 3760);
DISPLAY 0.659574 (-3515 3760);
PAINT MONO (-3515 3760);
DISPLAY INVISIBLE (-3515 3760);
FORCEPROP 1 LASTPIN (-3525 3750) BN 9
J 0
(-3537 3758);
DISPLAY 0.489362 (-3537 3758);
PAINT GREEN (-3537 3758);
FORCEPROP 2 LAST CDS_LIB mstr_standard
J 0
(-3475 3750);
DISPLAY 0.723404 (-3475 3750);
PAINT MONO (-3475 3750);
DISPLAY INVISIBLE (-3475 3750);
FORCEPROP 1 LAST BODY_TYPE PLUMBING
J 0
(-3475 3800);
DISPLAY 0.872340 (-3475 3800);
PAINT GREEN (-3475 3800);
DISPLAY INVISIBLE (-3475 3800);
FORCEPROP 1 LAST HDL_TAP TRUE
J 0
(-3150 3625);
DISPLAY 0.872340 (-3150 3625);
DISPLAY INVISIBLE (-3150 3625);
FORCEPROP 1 LAST PATH I203
J 0
(-3477 3750);
DISPLAY 0.872340 (-3477 3750);
PAINT GREEN (-3477 3750);
DISPLAY INVISIBLE (-3477 3750);
FORCEADD TAP..1
(-3475 3800);
FORCEPROP 3 LASTPIN (-3525 3800) SIG_NAME M_C_CPU1_SB_DQ<8>
J 0
(-3515 3810);
DISPLAY 0.659574 (-3515 3810);
PAINT MONO (-3515 3810);
DISPLAY INVISIBLE (-3515 3810);
FORCEPROP 1 LASTPIN (-3525 3800) BN 8
J 0
(-3537 3808);
DISPLAY 0.489362 (-3537 3808);
PAINT GREEN (-3537 3808);
FORCEPROP 2 LAST CDS_LIB mstr_standard
J 0
(-3475 3800);
DISPLAY 0.723404 (-3475 3800);
PAINT MONO (-3475 3800);
DISPLAY INVISIBLE (-3475 3800);
FORCEPROP 1 LAST BODY_TYPE PLUMBING
J 0
(-3475 3850);
DISPLAY 0.872340 (-3475 3850);
PAINT GREEN (-3475 3850);
DISPLAY INVISIBLE (-3475 3850);
FORCEPROP 1 LAST HDL_TAP TRUE
J 0
(-3150 3675);
DISPLAY 0.872340 (-3150 3675);
DISPLAY INVISIBLE (-3150 3675);
FORCEPROP 1 LAST PATH I204
J 0
(-3477 3800);
DISPLAY 0.872340 (-3477 3800);
PAINT GREEN (-3477 3800);
DISPLAY INVISIBLE (-3477 3800);
FORCEADD TAP..1
(-3475 3700);
FORCEPROP 3 LASTPIN (-3525 3700) SIG_NAME M_C_CPU1_SB_DQ<10>
J 0
(-3515 3710);
DISPLAY 0.659574 (-3515 3710);
PAINT MONO (-3515 3710);
DISPLAY INVISIBLE (-3515 3710);
FORCEPROP 1 LASTPIN (-3525 3700) BN 10
J 0
(-3537 3708);
DISPLAY 0.489362 (-3537 3708);
PAINT GREEN (-3537 3708);
FORCEPROP 2 LAST CDS_LIB mstr_standard
J 0
(-3475 3700);
DISPLAY 0.723404 (-3475 3700);
PAINT MONO (-3475 3700);
DISPLAY INVISIBLE (-3475 3700);
FORCEPROP 1 LAST BODY_TYPE PLUMBING
J 0
(-3475 3750);
DISPLAY 0.872340 (-3475 3750);
PAINT GREEN (-3475 3750);
DISPLAY INVISIBLE (-3475 3750);
FORCEPROP 1 LAST HDL_TAP TRUE
J 0
(-3150 3575);
DISPLAY 0.872340 (-3150 3575);
DISPLAY INVISIBLE (-3150 3575);
FORCEPROP 1 LAST PATH I205
J 0
(-3477 3700);
DISPLAY 0.872340 (-3477 3700);
PAINT GREEN (-3477 3700);
DISPLAY INVISIBLE (-3477 3700);
FORCEADD TAP..1
(-3475 3600);
FORCEPROP 3 LASTPIN (-3525 3600) SIG_NAME M_C_CPU1_SB_DQ<12>
J 0
(-3515 3610);
DISPLAY 0.659574 (-3515 3610);
PAINT MONO (-3515 3610);
DISPLAY INVISIBLE (-3515 3610);
FORCEPROP 1 LASTPIN (-3525 3600) BN 12
J 0
(-3537 3608);
DISPLAY 0.489362 (-3537 3608);
PAINT GREEN (-3537 3608);
FORCEPROP 2 LAST CDS_LIB mstr_standard
J 0
(-3475 3600);
DISPLAY 0.723404 (-3475 3600);
PAINT MONO (-3475 3600);
DISPLAY INVISIBLE (-3475 3600);
FORCEPROP 1 LAST BODY_TYPE PLUMBING
J 0
(-3475 3650);
DISPLAY 0.872340 (-3475 3650);
PAINT GREEN (-3475 3650);
DISPLAY INVISIBLE (-3475 3650);
FORCEPROP 1 LAST HDL_TAP TRUE
J 0
(-3150 3475);
DISPLAY 0.872340 (-3150 3475);
DISPLAY INVISIBLE (-3150 3475);
FORCEPROP 1 LAST PATH I206
J 0
(-3477 3600);
DISPLAY 0.872340 (-3477 3600);
PAINT GREEN (-3477 3600);
DISPLAY INVISIBLE (-3477 3600);
FORCEADD TAP..1
(-3475 3650);
FORCEPROP 3 LASTPIN (-3525 3650) SIG_NAME M_C_CPU1_SB_DQ<11>
J 0
(-3515 3660);
DISPLAY 0.659574 (-3515 3660);
PAINT MONO (-3515 3660);
DISPLAY INVISIBLE (-3515 3660);
FORCEPROP 1 LASTPIN (-3525 3650) BN 11
J 0
(-3537 3658);
DISPLAY 0.489362 (-3537 3658);
PAINT GREEN (-3537 3658);
FORCEPROP 2 LAST CDS_LIB mstr_standard
J 0
(-3475 3650);
DISPLAY 0.723404 (-3475 3650);
PAINT MONO (-3475 3650);
DISPLAY INVISIBLE (-3475 3650);
FORCEPROP 1 LAST BODY_TYPE PLUMBING
J 0
(-3475 3700);
DISPLAY 0.872340 (-3475 3700);
PAINT GREEN (-3475 3700);
DISPLAY INVISIBLE (-3475 3700);
FORCEPROP 1 LAST HDL_TAP TRUE
J 0
(-3150 3525);
DISPLAY 0.872340 (-3150 3525);
DISPLAY INVISIBLE (-3150 3525);
FORCEPROP 1 LAST PATH I207
J 0
(-3477 3650);
DISPLAY 0.872340 (-3477 3650);
PAINT GREEN (-3477 3650);
DISPLAY INVISIBLE (-3477 3650);
FORCEADD TAP..1
(-3475 3550);
FORCEPROP 3 LASTPIN (-3525 3550) SIG_NAME M_C_CPU1_SB_DQ<13>
J 0
(-3515 3560);
DISPLAY 0.659574 (-3515 3560);
PAINT MONO (-3515 3560);
DISPLAY INVISIBLE (-3515 3560);
FORCEPROP 1 LASTPIN (-3525 3550) BN 13
J 0
(-3537 3558);
DISPLAY 0.489362 (-3537 3558);
PAINT GREEN (-3537 3558);
FORCEPROP 2 LAST CDS_LIB mstr_standard
J 0
(-3475 3550);
DISPLAY 0.723404 (-3475 3550);
PAINT MONO (-3475 3550);
DISPLAY INVISIBLE (-3475 3550);
FORCEPROP 1 LAST BODY_TYPE PLUMBING
J 0
(-3475 3600);
DISPLAY 0.872340 (-3475 3600);
PAINT GREEN (-3475 3600);
DISPLAY INVISIBLE (-3475 3600);
FORCEPROP 1 LAST HDL_TAP TRUE
J 0
(-3150 3425);
DISPLAY 0.872340 (-3150 3425);
DISPLAY INVISIBLE (-3150 3425);
FORCEPROP 1 LAST PATH I208
J 0
(-3477 3550);
DISPLAY 0.872340 (-3477 3550);
PAINT GREEN (-3477 3550);
DISPLAY INVISIBLE (-3477 3550);
FORCEADD TAP..1
(-3475 3450);
FORCEPROP 3 LASTPIN (-3525 3450) SIG_NAME M_C_CPU1_SB_DQ<15>
J 0
(-3515 3460);
DISPLAY 0.659574 (-3515 3460);
PAINT MONO (-3515 3460);
DISPLAY INVISIBLE (-3515 3460);
FORCEPROP 1 LASTPIN (-3525 3450) BN 15
J 0
(-3537 3458);
DISPLAY 0.489362 (-3537 3458);
PAINT GREEN (-3537 3458);
FORCEPROP 2 LAST CDS_LIB mstr_standard
J 0
(-3475 3450);
DISPLAY 0.723404 (-3475 3450);
PAINT MONO (-3475 3450);
DISPLAY INVISIBLE (-3475 3450);
FORCEPROP 1 LAST BODY_TYPE PLUMBING
J 0
(-3475 3500);
DISPLAY 0.872340 (-3475 3500);
PAINT GREEN (-3475 3500);
DISPLAY INVISIBLE (-3475 3500);
FORCEPROP 1 LAST HDL_TAP TRUE
J 0
(-3150 3325);
DISPLAY 0.872340 (-3150 3325);
DISPLAY INVISIBLE (-3150 3325);
FORCEPROP 1 LAST PATH I209
J 0
(-3477 3450);
DISPLAY 0.872340 (-3477 3450);
PAINT GREEN (-3477 3450);
DISPLAY INVISIBLE (-3477 3450);
FORCEADD TAP..1
(-3475 3500);
FORCEPROP 3 LASTPIN (-3525 3500) SIG_NAME M_C_CPU1_SB_DQ<14>
J 0
(-3515 3510);
DISPLAY 0.659574 (-3515 3510);
PAINT MONO (-3515 3510);
DISPLAY INVISIBLE (-3515 3510);
FORCEPROP 1 LASTPIN (-3525 3500) BN 14
J 0
(-3537 3508);
DISPLAY 0.489362 (-3537 3508);
PAINT GREEN (-3537 3508);
FORCEPROP 2 LAST CDS_LIB mstr_standard
J 0
(-3475 3500);
DISPLAY 0.723404 (-3475 3500);
PAINT MONO (-3475 3500);
DISPLAY INVISIBLE (-3475 3500);
FORCEPROP 1 LAST BODY_TYPE PLUMBING
J 0
(-3475 3550);
DISPLAY 0.872340 (-3475 3550);
PAINT GREEN (-3475 3550);
DISPLAY INVISIBLE (-3475 3550);
FORCEPROP 1 LAST HDL_TAP TRUE
J 0
(-3150 3375);
DISPLAY 0.872340 (-3150 3375);
DISPLAY INVISIBLE (-3150 3375);
FORCEPROP 1 LAST PATH I210
J 0
(-3477 3500);
DISPLAY 0.872340 (-3477 3500);
PAINT GREEN (-3477 3500);
DISPLAY INVISIBLE (-3477 3500);
FORCEADD TAP..1
(-3475 3350);
FORCEPROP 3 LASTPIN (-3525 3350) SIG_NAME M_C_CPU1_SB_DQ<16>
J 0
(-3515 3360);
DISPLAY 0.659574 (-3515 3360);
PAINT MONO (-3515 3360);
DISPLAY INVISIBLE (-3515 3360);
FORCEPROP 1 LASTPIN (-3525 3350) BN 16
J 0
(-3537 3358);
DISPLAY 0.489362 (-3537 3358);
PAINT GREEN (-3537 3358);
FORCEPROP 2 LAST CDS_LIB mstr_standard
J 0
(-3475 3350);
DISPLAY 0.723404 (-3475 3350);
PAINT MONO (-3475 3350);
DISPLAY INVISIBLE (-3475 3350);
FORCEPROP 1 LAST BODY_TYPE PLUMBING
J 0
(-3475 3400);
DISPLAY 0.872340 (-3475 3400);
PAINT GREEN (-3475 3400);
DISPLAY INVISIBLE (-3475 3400);
FORCEPROP 1 LAST HDL_TAP TRUE
J 0
(-3150 3225);
DISPLAY 0.872340 (-3150 3225);
DISPLAY INVISIBLE (-3150 3225);
FORCEPROP 1 LAST PATH I211
J 0
(-3477 3350);
DISPLAY 0.872340 (-3477 3350);
PAINT GREEN (-3477 3350);
DISPLAY INVISIBLE (-3477 3350);
FORCEADD TAP..1
(-3475 3250);
FORCEPROP 3 LASTPIN (-3525 3250) SIG_NAME M_C_CPU1_SB_DQ<18>
J 0
(-3515 3260);
DISPLAY 0.659574 (-3515 3260);
PAINT MONO (-3515 3260);
DISPLAY INVISIBLE (-3515 3260);
FORCEPROP 1 LASTPIN (-3525 3250) BN 18
J 0
(-3537 3258);
DISPLAY 0.489362 (-3537 3258);
PAINT GREEN (-3537 3258);
FORCEPROP 2 LAST CDS_LIB mstr_standard
J 0
(-3475 3250);
DISPLAY 0.723404 (-3475 3250);
PAINT MONO (-3475 3250);
DISPLAY INVISIBLE (-3475 3250);
FORCEPROP 1 LAST BODY_TYPE PLUMBING
J 0
(-3475 3300);
DISPLAY 0.872340 (-3475 3300);
PAINT GREEN (-3475 3300);
DISPLAY INVISIBLE (-3475 3300);
FORCEPROP 1 LAST HDL_TAP TRUE
J 0
(-3150 3125);
DISPLAY 0.872340 (-3150 3125);
DISPLAY INVISIBLE (-3150 3125);
FORCEPROP 1 LAST PATH I212
J 0
(-3477 3250);
DISPLAY 0.872340 (-3477 3250);
PAINT GREEN (-3477 3250);
DISPLAY INVISIBLE (-3477 3250);
FORCEADD TAP..1
(-3475 3300);
FORCEPROP 3 LASTPIN (-3525 3300) SIG_NAME M_C_CPU1_SB_DQ<17>
J 0
(-3515 3310);
DISPLAY 0.659574 (-3515 3310);
PAINT MONO (-3515 3310);
DISPLAY INVISIBLE (-3515 3310);
FORCEPROP 1 LASTPIN (-3525 3300) BN 17
J 0
(-3537 3308);
DISPLAY 0.489362 (-3537 3308);
PAINT GREEN (-3537 3308);
FORCEPROP 2 LAST CDS_LIB mstr_standard
J 0
(-3475 3300);
DISPLAY 0.723404 (-3475 3300);
PAINT MONO (-3475 3300);
DISPLAY INVISIBLE (-3475 3300);
FORCEPROP 1 LAST BODY_TYPE PLUMBING
J 0
(-3475 3350);
DISPLAY 0.872340 (-3475 3350);
PAINT GREEN (-3475 3350);
DISPLAY INVISIBLE (-3475 3350);
FORCEPROP 1 LAST HDL_TAP TRUE
J 0
(-3150 3175);
DISPLAY 0.872340 (-3150 3175);
DISPLAY INVISIBLE (-3150 3175);
FORCEPROP 1 LAST PATH I213
J 0
(-3477 3300);
DISPLAY 0.872340 (-3477 3300);
PAINT GREEN (-3477 3300);
DISPLAY INVISIBLE (-3477 3300);
FORCEADD TAP..1
(-3475 3200);
FORCEPROP 3 LASTPIN (-3525 3200) SIG_NAME M_C_CPU1_SB_DQ<19>
J 0
(-3515 3210);
DISPLAY 0.659574 (-3515 3210);
PAINT MONO (-3515 3210);
DISPLAY INVISIBLE (-3515 3210);
FORCEPROP 1 LASTPIN (-3525 3200) BN 19
J 0
(-3537 3208);
DISPLAY 0.489362 (-3537 3208);
PAINT GREEN (-3537 3208);
FORCEPROP 2 LAST CDS_LIB mstr_standard
J 0
(-3475 3200);
DISPLAY 0.723404 (-3475 3200);
PAINT MONO (-3475 3200);
DISPLAY INVISIBLE (-3475 3200);
FORCEPROP 1 LAST BODY_TYPE PLUMBING
J 0
(-3475 3250);
DISPLAY 0.872340 (-3475 3250);
PAINT GREEN (-3475 3250);
DISPLAY INVISIBLE (-3475 3250);
FORCEPROP 1 LAST HDL_TAP TRUE
J 0
(-3150 3075);
DISPLAY 0.872340 (-3150 3075);
DISPLAY INVISIBLE (-3150 3075);
FORCEPROP 1 LAST PATH I214
J 0
(-3477 3200);
DISPLAY 0.872340 (-3477 3200);
PAINT GREEN (-3477 3200);
DISPLAY INVISIBLE (-3477 3200);
FORCEADD TAP..1
(-3475 3100);
FORCEPROP 3 LASTPIN (-3525 3100) SIG_NAME M_C_CPU1_SB_DQ<21>
J 0
(-3515 3110);
DISPLAY 0.659574 (-3515 3110);
PAINT MONO (-3515 3110);
DISPLAY INVISIBLE (-3515 3110);
FORCEPROP 1 LASTPIN (-3525 3100) BN 21
J 0
(-3537 3108);
DISPLAY 0.489362 (-3537 3108);
PAINT GREEN (-3537 3108);
FORCEPROP 2 LAST CDS_LIB mstr_standard
J 0
(-3475 3100);
DISPLAY 0.723404 (-3475 3100);
PAINT MONO (-3475 3100);
DISPLAY INVISIBLE (-3475 3100);
FORCEPROP 1 LAST BODY_TYPE PLUMBING
J 0
(-3475 3150);
DISPLAY 0.872340 (-3475 3150);
PAINT GREEN (-3475 3150);
DISPLAY INVISIBLE (-3475 3150);
FORCEPROP 1 LAST HDL_TAP TRUE
J 0
(-3150 2975);
DISPLAY 0.872340 (-3150 2975);
DISPLAY INVISIBLE (-3150 2975);
FORCEPROP 1 LAST PATH I215
J 0
(-3477 3100);
DISPLAY 0.872340 (-3477 3100);
PAINT GREEN (-3477 3100);
DISPLAY INVISIBLE (-3477 3100);
FORCEADD TAP..1
(-3475 3150);
FORCEPROP 3 LASTPIN (-3525 3150) SIG_NAME M_C_CPU1_SB_DQ<20>
J 0
(-3515 3160);
DISPLAY 0.659574 (-3515 3160);
PAINT MONO (-3515 3160);
DISPLAY INVISIBLE (-3515 3160);
FORCEPROP 1 LASTPIN (-3525 3150) BN 20
J 0
(-3537 3158);
DISPLAY 0.489362 (-3537 3158);
PAINT GREEN (-3537 3158);
FORCEPROP 2 LAST CDS_LIB mstr_standard
J 0
(-3475 3150);
DISPLAY 0.723404 (-3475 3150);
PAINT MONO (-3475 3150);
DISPLAY INVISIBLE (-3475 3150);
FORCEPROP 1 LAST BODY_TYPE PLUMBING
J 0
(-3475 3200);
DISPLAY 0.872340 (-3475 3200);
PAINT GREEN (-3475 3200);
DISPLAY INVISIBLE (-3475 3200);
FORCEPROP 1 LAST HDL_TAP TRUE
J 0
(-3150 3025);
DISPLAY 0.872340 (-3150 3025);
DISPLAY INVISIBLE (-3150 3025);
FORCEPROP 1 LAST PATH I216
J 0
(-3477 3150);
DISPLAY 0.872340 (-3477 3150);
PAINT GREEN (-3477 3150);
DISPLAY INVISIBLE (-3477 3150);
FORCEADD TAP..1
(-3475 3050);
FORCEPROP 3 LASTPIN (-3525 3050) SIG_NAME M_C_CPU1_SB_DQ<22>
J 0
(-3515 3060);
DISPLAY 0.659574 (-3515 3060);
PAINT MONO (-3515 3060);
DISPLAY INVISIBLE (-3515 3060);
FORCEPROP 1 LASTPIN (-3525 3050) BN 22
J 0
(-3537 3058);
DISPLAY 0.489362 (-3537 3058);
PAINT GREEN (-3537 3058);
FORCEPROP 2 LAST CDS_LIB mstr_standard
J 0
(-3475 3050);
DISPLAY 0.723404 (-3475 3050);
PAINT MONO (-3475 3050);
DISPLAY INVISIBLE (-3475 3050);
FORCEPROP 1 LAST BODY_TYPE PLUMBING
J 0
(-3475 3100);
DISPLAY 0.872340 (-3475 3100);
PAINT GREEN (-3475 3100);
DISPLAY INVISIBLE (-3475 3100);
FORCEPROP 1 LAST HDL_TAP TRUE
J 0
(-3150 2925);
DISPLAY 0.872340 (-3150 2925);
DISPLAY INVISIBLE (-3150 2925);
FORCEPROP 1 LAST PATH I217
J 0
(-3477 3050);
DISPLAY 0.872340 (-3477 3050);
PAINT GREEN (-3477 3050);
DISPLAY INVISIBLE (-3477 3050);
FORCEADD TAP..1
(-3475 2900);
FORCEPROP 3 LASTPIN (-3525 2900) SIG_NAME M_C_CPU1_SB_DQ<24>
J 0
(-3515 2910);
DISPLAY 0.659574 (-3515 2910);
PAINT MONO (-3515 2910);
DISPLAY INVISIBLE (-3515 2910);
FORCEPROP 1 LASTPIN (-3525 2900) BN 24
J 0
(-3537 2908);
DISPLAY 0.489362 (-3537 2908);
PAINT GREEN (-3537 2908);
FORCEPROP 2 LAST CDS_LIB mstr_standard
J 0
(-3475 2900);
DISPLAY 0.723404 (-3475 2900);
PAINT MONO (-3475 2900);
DISPLAY INVISIBLE (-3475 2900);
FORCEPROP 1 LAST BODY_TYPE PLUMBING
J 0
(-3475 2950);
DISPLAY 0.872340 (-3475 2950);
PAINT GREEN (-3475 2950);
DISPLAY INVISIBLE (-3475 2950);
FORCEPROP 1 LAST HDL_TAP TRUE
J 0
(-3150 2775);
DISPLAY 0.872340 (-3150 2775);
DISPLAY INVISIBLE (-3150 2775);
FORCEPROP 1 LAST PATH I218
J 0
(-3477 2900);
DISPLAY 0.872340 (-3477 2900);
PAINT GREEN (-3477 2900);
DISPLAY INVISIBLE (-3477 2900);
FORCEADD TAP..1
(-3475 2850);
FORCEPROP 3 LASTPIN (-3525 2850) SIG_NAME M_C_CPU1_SB_DQ<25>
J 0
(-3515 2860);
DISPLAY 0.659574 (-3515 2860);
PAINT MONO (-3515 2860);
DISPLAY INVISIBLE (-3515 2860);
FORCEPROP 1 LASTPIN (-3525 2850) BN 25
J 0
(-3537 2858);
DISPLAY 0.489362 (-3537 2858);
PAINT GREEN (-3537 2858);
FORCEPROP 2 LAST CDS_LIB mstr_standard
J 0
(-3475 2850);
DISPLAY 0.723404 (-3475 2850);
PAINT MONO (-3475 2850);
DISPLAY INVISIBLE (-3475 2850);
FORCEPROP 1 LAST BODY_TYPE PLUMBING
J 0
(-3475 2900);
DISPLAY 0.872340 (-3475 2900);
PAINT GREEN (-3475 2900);
DISPLAY INVISIBLE (-3475 2900);
FORCEPROP 1 LAST HDL_TAP TRUE
J 0
(-3150 2725);
DISPLAY 0.872340 (-3150 2725);
DISPLAY INVISIBLE (-3150 2725);
FORCEPROP 1 LAST PATH I219
J 0
(-3477 2850);
DISPLAY 0.872340 (-3477 2850);
PAINT GREEN (-3477 2850);
DISPLAY INVISIBLE (-3477 2850);
FORCEADD TAP..1
(-3475 3000);
FORCEPROP 3 LASTPIN (-3525 3000) SIG_NAME M_C_CPU1_SB_DQ<23>
J 0
(-3515 3010);
DISPLAY 0.659574 (-3515 3010);
PAINT MONO (-3515 3010);
DISPLAY INVISIBLE (-3515 3010);
FORCEPROP 1 LASTPIN (-3525 3000) BN 23
J 0
(-3537 3008);
DISPLAY 0.489362 (-3537 3008);
PAINT GREEN (-3537 3008);
FORCEPROP 2 LAST CDS_LIB mstr_standard
J 0
(-3475 3000);
DISPLAY 0.723404 (-3475 3000);
PAINT MONO (-3475 3000);
DISPLAY INVISIBLE (-3475 3000);
FORCEPROP 1 LAST BODY_TYPE PLUMBING
J 0
(-3475 3050);
DISPLAY 0.872340 (-3475 3050);
PAINT GREEN (-3475 3050);
DISPLAY INVISIBLE (-3475 3050);
FORCEPROP 1 LAST HDL_TAP TRUE
J 0
(-3150 2875);
DISPLAY 0.872340 (-3150 2875);
DISPLAY INVISIBLE (-3150 2875);
FORCEPROP 1 LAST PATH I220
J 0
(-3477 3000);
DISPLAY 0.872340 (-3477 3000);
PAINT GREEN (-3477 3000);
DISPLAY INVISIBLE (-3477 3000);
FORCEADD TAP..1
(-3475 2750);
FORCEPROP 3 LASTPIN (-3525 2750) SIG_NAME M_C_CPU1_SB_DQ<27>
J 0
(-3515 2760);
DISPLAY 0.659574 (-3515 2760);
PAINT MONO (-3515 2760);
DISPLAY INVISIBLE (-3515 2760);
FORCEPROP 1 LASTPIN (-3525 2750) BN 27
J 0
(-3537 2758);
DISPLAY 0.489362 (-3537 2758);
PAINT GREEN (-3537 2758);
FORCEPROP 2 LAST CDS_LIB mstr_standard
J 0
(-3475 2750);
DISPLAY 0.723404 (-3475 2750);
PAINT MONO (-3475 2750);
DISPLAY INVISIBLE (-3475 2750);
FORCEPROP 1 LAST BODY_TYPE PLUMBING
J 0
(-3475 2800);
DISPLAY 0.872340 (-3475 2800);
PAINT GREEN (-3475 2800);
DISPLAY INVISIBLE (-3475 2800);
FORCEPROP 1 LAST HDL_TAP TRUE
J 0
(-3150 2625);
DISPLAY 0.872340 (-3150 2625);
DISPLAY INVISIBLE (-3150 2625);
FORCEPROP 1 LAST PATH I221
J 0
(-3477 2750);
DISPLAY 0.872340 (-3477 2750);
PAINT GREEN (-3477 2750);
DISPLAY INVISIBLE (-3477 2750);
FORCEADD TAP..1
(-3475 2700);
FORCEPROP 3 LASTPIN (-3525 2700) SIG_NAME M_C_CPU1_SB_DQ<28>
J 0
(-3515 2710);
DISPLAY 0.659574 (-3515 2710);
PAINT MONO (-3515 2710);
DISPLAY INVISIBLE (-3515 2710);
FORCEPROP 1 LASTPIN (-3525 2700) BN 28
J 0
(-3537 2708);
DISPLAY 0.489362 (-3537 2708);
PAINT GREEN (-3537 2708);
FORCEPROP 2 LAST CDS_LIB mstr_standard
J 0
(-3475 2700);
DISPLAY 0.723404 (-3475 2700);
PAINT MONO (-3475 2700);
DISPLAY INVISIBLE (-3475 2700);
FORCEPROP 1 LAST BODY_TYPE PLUMBING
J 0
(-3475 2750);
DISPLAY 0.872340 (-3475 2750);
PAINT GREEN (-3475 2750);
DISPLAY INVISIBLE (-3475 2750);
FORCEPROP 1 LAST HDL_TAP TRUE
J 0
(-3150 2575);
DISPLAY 0.872340 (-3150 2575);
DISPLAY INVISIBLE (-3150 2575);
FORCEPROP 1 LAST PATH I222
J 0
(-3477 2700);
DISPLAY 0.872340 (-3477 2700);
PAINT GREEN (-3477 2700);
DISPLAY INVISIBLE (-3477 2700);
FORCEADD TAP..1
(-3475 2800);
FORCEPROP 3 LASTPIN (-3525 2800) SIG_NAME M_C_CPU1_SB_DQ<26>
J 0
(-3515 2810);
DISPLAY 0.659574 (-3515 2810);
PAINT MONO (-3515 2810);
DISPLAY INVISIBLE (-3515 2810);
FORCEPROP 1 LASTPIN (-3525 2800) BN 26
J 0
(-3537 2808);
DISPLAY 0.489362 (-3537 2808);
PAINT GREEN (-3537 2808);
FORCEPROP 2 LAST CDS_LIB mstr_standard
J 0
(-3475 2800);
DISPLAY 0.723404 (-3475 2800);
PAINT MONO (-3475 2800);
DISPLAY INVISIBLE (-3475 2800);
FORCEPROP 1 LAST BODY_TYPE PLUMBING
J 0
(-3475 2850);
DISPLAY 0.872340 (-3475 2850);
PAINT GREEN (-3475 2850);
DISPLAY INVISIBLE (-3475 2850);
FORCEPROP 1 LAST HDL_TAP TRUE
J 0
(-3150 2675);
DISPLAY 0.872340 (-3150 2675);
DISPLAY INVISIBLE (-3150 2675);
FORCEPROP 1 LAST PATH I223
J 0
(-3477 2800);
DISPLAY 0.872340 (-3477 2800);
PAINT GREEN (-3477 2800);
DISPLAY INVISIBLE (-3477 2800);
FORCEADD TAP..1
(-3475 2650);
FORCEPROP 3 LASTPIN (-3525 2650) SIG_NAME M_C_CPU1_SB_DQ<29>
J 0
(-3515 2660);
DISPLAY 0.659574 (-3515 2660);
PAINT MONO (-3515 2660);
DISPLAY INVISIBLE (-3515 2660);
FORCEPROP 1 LASTPIN (-3525 2650) BN 29
J 0
(-3537 2658);
DISPLAY 0.489362 (-3537 2658);
PAINT GREEN (-3537 2658);
FORCEPROP 2 LAST CDS_LIB mstr_standard
J 0
(-3475 2650);
DISPLAY 0.723404 (-3475 2650);
PAINT MONO (-3475 2650);
DISPLAY INVISIBLE (-3475 2650);
FORCEPROP 1 LAST BODY_TYPE PLUMBING
J 0
(-3475 2700);
DISPLAY 0.872340 (-3475 2700);
PAINT GREEN (-3475 2700);
DISPLAY INVISIBLE (-3475 2700);
FORCEPROP 1 LAST HDL_TAP TRUE
J 0
(-3150 2525);
DISPLAY 0.872340 (-3150 2525);
DISPLAY INVISIBLE (-3150 2525);
FORCEPROP 1 LAST PATH I224
J 0
(-3477 2650);
DISPLAY 0.872340 (-3477 2650);
PAINT GREEN (-3477 2650);
DISPLAY INVISIBLE (-3477 2650);
FORCEADD TAP..1
(-3475 2600);
FORCEPROP 3 LASTPIN (-3525 2600) SIG_NAME M_C_CPU1_SB_DQ<30>
J 0
(-3515 2610);
DISPLAY 0.659574 (-3515 2610);
PAINT MONO (-3515 2610);
DISPLAY INVISIBLE (-3515 2610);
FORCEPROP 1 LASTPIN (-3525 2600) BN 30
J 0
(-3537 2608);
DISPLAY 0.489362 (-3537 2608);
PAINT GREEN (-3537 2608);
FORCEPROP 2 LAST CDS_LIB mstr_standard
J 0
(-3475 2600);
DISPLAY 0.723404 (-3475 2600);
PAINT MONO (-3475 2600);
DISPLAY INVISIBLE (-3475 2600);
FORCEPROP 1 LAST BODY_TYPE PLUMBING
J 0
(-3475 2650);
DISPLAY 0.872340 (-3475 2650);
PAINT GREEN (-3475 2650);
DISPLAY INVISIBLE (-3475 2650);
FORCEPROP 1 LAST HDL_TAP TRUE
J 0
(-3150 2475);
DISPLAY 0.872340 (-3150 2475);
DISPLAY INVISIBLE (-3150 2475);
FORCEPROP 1 LAST PATH I225
J 0
(-3477 2600);
DISPLAY 0.872340 (-3477 2600);
PAINT GREEN (-3477 2600);
DISPLAY INVISIBLE (-3477 2600);
FORCEADD TAP..1
(-3475 2400);
FORCEPROP 3 LASTPIN (-3525 2400) SIG_NAME M_C_CPU1_SA_CB<1>
J 0
(-3515 2410);
DISPLAY 0.659574 (-3515 2410);
PAINT MONO (-3515 2410);
DISPLAY INVISIBLE (-3515 2410);
FORCEPROP 1 LASTPIN (-3525 2400) BN 1
J 0
(-3537 2408);
DISPLAY 0.489362 (-3537 2408);
PAINT GREEN (-3537 2408);
FORCEPROP 2 LAST CDS_LIB mstr_standard
J 2
(-3475 2400);
DISPLAY 0.723404 (-3475 2400);
PAINT MONO (-3475 2400);
DISPLAY INVISIBLE (-3475 2400);
FORCEPROP 1 LAST BODY_TYPE PLUMBING
J 0
(-3475 2450);
DISPLAY 0.872340 (-3475 2450);
PAINT GREEN (-3475 2450);
DISPLAY INVISIBLE (-3475 2450);
FORCEPROP 1 LAST HDL_TAP TRUE
J 0
(-3150 2275);
DISPLAY 0.872340 (-3150 2275);
DISPLAY INVISIBLE (-3150 2275);
FORCEPROP 1 LAST PATH I226
J 0
(-3477 2400);
DISPLAY 0.872340 (-3477 2400);
PAINT GREEN (-3477 2400);
DISPLAY INVISIBLE (-3477 2400);
FORCEADD TAP..1
(-3475 2350);
FORCEPROP 3 LASTPIN (-3525 2350) SIG_NAME M_C_CPU1_SA_CB<2>
J 0
(-3515 2360);
DISPLAY 0.659574 (-3515 2360);
PAINT MONO (-3515 2360);
DISPLAY INVISIBLE (-3515 2360);
FORCEPROP 1 LASTPIN (-3525 2350) BN 2
J 0
(-3537 2358);
DISPLAY 0.489362 (-3537 2358);
PAINT GREEN (-3537 2358);
FORCEPROP 2 LAST CDS_LIB mstr_standard
J 2
(-3475 2350);
DISPLAY 0.723404 (-3475 2350);
PAINT MONO (-3475 2350);
DISPLAY INVISIBLE (-3475 2350);
FORCEPROP 1 LAST BODY_TYPE PLUMBING
J 0
(-3475 2400);
DISPLAY 0.872340 (-3475 2400);
PAINT GREEN (-3475 2400);
DISPLAY INVISIBLE (-3475 2400);
FORCEPROP 1 LAST HDL_TAP TRUE
J 0
(-3150 2225);
DISPLAY 0.872340 (-3150 2225);
DISPLAY INVISIBLE (-3150 2225);
FORCEPROP 1 LAST PATH I227
J 0
(-3477 2350);
DISPLAY 0.872340 (-3477 2350);
PAINT GREEN (-3477 2350);
DISPLAY INVISIBLE (-3477 2350);
FORCEADD TAP..1
(-3475 2550);
FORCEPROP 3 LASTPIN (-3525 2550) SIG_NAME M_C_CPU1_SB_DQ<31>
J 0
(-3515 2560);
DISPLAY 0.659574 (-3515 2560);
PAINT MONO (-3515 2560);
DISPLAY INVISIBLE (-3515 2560);
FORCEPROP 1 LASTPIN (-3525 2550) BN 31
J 0
(-3537 2558);
DISPLAY 0.489362 (-3537 2558);
PAINT GREEN (-3537 2558);
FORCEPROP 2 LAST CDS_LIB mstr_standard
J 0
(-3475 2550);
DISPLAY 0.723404 (-3475 2550);
PAINT MONO (-3475 2550);
DISPLAY INVISIBLE (-3475 2550);
FORCEPROP 1 LAST BODY_TYPE PLUMBING
J 0
(-3475 2600);
DISPLAY 0.872340 (-3475 2600);
PAINT GREEN (-3475 2600);
DISPLAY INVISIBLE (-3475 2600);
FORCEPROP 1 LAST HDL_TAP TRUE
J 0
(-3150 2425);
DISPLAY 0.872340 (-3150 2425);
DISPLAY INVISIBLE (-3150 2425);
FORCEPROP 1 LAST PATH I228
J 0
(-3477 2550);
DISPLAY 0.872340 (-3477 2550);
PAINT GREEN (-3477 2550);
DISPLAY INVISIBLE (-3477 2550);
FORCEADD TAP..1
(-3475 2450);
FORCEPROP 3 LASTPIN (-3525 2450) SIG_NAME M_C_CPU1_SA_CB<0>
J 0
(-3515 2460);
DISPLAY 0.659574 (-3515 2460);
PAINT MONO (-3515 2460);
DISPLAY INVISIBLE (-3515 2460);
FORCEPROP 1 LASTPIN (-3525 2450) BN 0
J 0
(-3537 2458);
DISPLAY 0.489362 (-3537 2458);
PAINT GREEN (-3537 2458);
FORCEPROP 2 LAST CDS_LIB mstr_standard
J 2
(-3475 2450);
DISPLAY 0.723404 (-3475 2450);
PAINT MONO (-3475 2450);
DISPLAY INVISIBLE (-3475 2450);
FORCEPROP 1 LAST BODY_TYPE PLUMBING
J 0
(-3475 2500);
DISPLAY 0.872340 (-3475 2500);
PAINT GREEN (-3475 2500);
DISPLAY INVISIBLE (-3475 2500);
FORCEPROP 1 LAST HDL_TAP TRUE
J 0
(-3150 2325);
DISPLAY 0.872340 (-3150 2325);
DISPLAY INVISIBLE (-3150 2325);
FORCEPROP 1 LAST PATH I229
J 0
(-3477 2450);
DISPLAY 0.872340 (-3477 2450);
PAINT GREEN (-3477 2450);
DISPLAY INVISIBLE (-3477 2450);
FORCEADD TAP..1
(-3475 2200);
FORCEPROP 3 LASTPIN (-3525 2200) SIG_NAME M_C_CPU1_SA_CB<5>
J 0
(-3515 2210);
DISPLAY 0.659574 (-3515 2210);
PAINT MONO (-3515 2210);
DISPLAY INVISIBLE (-3515 2210);
FORCEPROP 1 LASTPIN (-3525 2200) BN 5
J 0
(-3537 2208);
DISPLAY 0.489362 (-3537 2208);
PAINT GREEN (-3537 2208);
FORCEPROP 2 LAST CDS_LIB mstr_standard
J 2
(-3475 2200);
DISPLAY 0.723404 (-3475 2200);
PAINT MONO (-3475 2200);
DISPLAY INVISIBLE (-3475 2200);
FORCEPROP 1 LAST BODY_TYPE PLUMBING
J 0
(-3475 2250);
DISPLAY 0.872340 (-3475 2250);
PAINT GREEN (-3475 2250);
DISPLAY INVISIBLE (-3475 2250);
FORCEPROP 1 LAST HDL_TAP TRUE
J 0
(-3150 2075);
DISPLAY 0.872340 (-3150 2075);
DISPLAY INVISIBLE (-3150 2075);
FORCEPROP 1 LAST PATH I230
J 0
(-3477 2200);
DISPLAY 0.872340 (-3477 2200);
PAINT GREEN (-3477 2200);
DISPLAY INVISIBLE (-3477 2200);
FORCEADD TAP..1
(-3475 2250);
FORCEPROP 3 LASTPIN (-3525 2250) SIG_NAME M_C_CPU1_SA_CB<4>
J 0
(-3515 2260);
DISPLAY 0.659574 (-3515 2260);
PAINT MONO (-3515 2260);
DISPLAY INVISIBLE (-3515 2260);
FORCEPROP 1 LASTPIN (-3525 2250) BN 4
J 0
(-3537 2258);
DISPLAY 0.489362 (-3537 2258);
PAINT GREEN (-3537 2258);
FORCEPROP 2 LAST CDS_LIB mstr_standard
J 2
(-3475 2250);
DISPLAY 0.723404 (-3475 2250);
PAINT MONO (-3475 2250);
DISPLAY INVISIBLE (-3475 2250);
FORCEPROP 1 LAST BODY_TYPE PLUMBING
J 0
(-3475 2300);
DISPLAY 0.872340 (-3475 2300);
PAINT GREEN (-3475 2300);
DISPLAY INVISIBLE (-3475 2300);
FORCEPROP 1 LAST HDL_TAP TRUE
J 0
(-3150 2125);
DISPLAY 0.872340 (-3150 2125);
DISPLAY INVISIBLE (-3150 2125);
FORCEPROP 1 LAST PATH I231
J 0
(-3477 2250);
DISPLAY 0.872340 (-3477 2250);
PAINT GREEN (-3477 2250);
DISPLAY INVISIBLE (-3477 2250);
FORCEADD TAP..1
(-3475 2300);
FORCEPROP 3 LASTPIN (-3525 2300) SIG_NAME M_C_CPU1_SA_CB<3>
J 0
(-3515 2310);
DISPLAY 0.659574 (-3515 2310);
PAINT MONO (-3515 2310);
DISPLAY INVISIBLE (-3515 2310);
FORCEPROP 1 LASTPIN (-3525 2300) BN 3
J 0
(-3537 2308);
DISPLAY 0.489362 (-3537 2308);
PAINT GREEN (-3537 2308);
FORCEPROP 2 LAST CDS_LIB mstr_standard
J 2
(-3475 2300);
DISPLAY 0.723404 (-3475 2300);
PAINT MONO (-3475 2300);
DISPLAY INVISIBLE (-3475 2300);
FORCEPROP 1 LAST BODY_TYPE PLUMBING
J 0
(-3475 2350);
DISPLAY 0.872340 (-3475 2350);
PAINT GREEN (-3475 2350);
DISPLAY INVISIBLE (-3475 2350);
FORCEPROP 1 LAST HDL_TAP TRUE
J 0
(-3150 2175);
DISPLAY 0.872340 (-3150 2175);
DISPLAY INVISIBLE (-3150 2175);
FORCEPROP 1 LAST PATH I232
J 0
(-3477 2300);
DISPLAY 0.872340 (-3477 2300);
PAINT GREEN (-3477 2300);
DISPLAY INVISIBLE (-3477 2300);
FORCEADD TAP..1
(-3475 2150);
FORCEPROP 3 LASTPIN (-3525 2150) SIG_NAME M_C_CPU1_SA_CB<6>
J 0
(-3515 2160);
DISPLAY 0.659574 (-3515 2160);
PAINT MONO (-3515 2160);
DISPLAY INVISIBLE (-3515 2160);
FORCEPROP 1 LASTPIN (-3525 2150) BN 6
J 0
(-3537 2158);
DISPLAY 0.489362 (-3537 2158);
PAINT GREEN (-3537 2158);
FORCEPROP 2 LAST CDS_LIB mstr_standard
J 2
(-3475 2150);
DISPLAY 0.723404 (-3475 2150);
PAINT MONO (-3475 2150);
DISPLAY INVISIBLE (-3475 2150);
FORCEPROP 1 LAST BODY_TYPE PLUMBING
J 0
(-3475 2200);
DISPLAY 0.872340 (-3475 2200);
PAINT GREEN (-3475 2200);
DISPLAY INVISIBLE (-3475 2200);
FORCEPROP 1 LAST HDL_TAP TRUE
J 0
(-3150 2025);
DISPLAY 0.872340 (-3150 2025);
DISPLAY INVISIBLE (-3150 2025);
FORCEPROP 1 LAST PATH I233
J 0
(-3477 2150);
DISPLAY 0.872340 (-3477 2150);
PAINT GREEN (-3477 2150);
DISPLAY INVISIBLE (-3477 2150);
FORCEADD TAP..1
(-3475 2100);
FORCEPROP 3 LASTPIN (-3525 2100) SIG_NAME M_C_CPU1_SA_CB<7>
J 0
(-3515 2110);
DISPLAY 0.659574 (-3515 2110);
PAINT MONO (-3515 2110);
DISPLAY INVISIBLE (-3515 2110);
FORCEPROP 1 LASTPIN (-3525 2100) BN 7
J 0
(-3537 2108);
DISPLAY 0.489362 (-3537 2108);
PAINT GREEN (-3537 2108);
FORCEPROP 2 LAST CDS_LIB mstr_standard
J 2
(-3475 2100);
DISPLAY 0.723404 (-3475 2100);
PAINT MONO (-3475 2100);
DISPLAY INVISIBLE (-3475 2100);
FORCEPROP 1 LAST BODY_TYPE PLUMBING
J 0
(-3475 2150);
DISPLAY 0.872340 (-3475 2150);
PAINT GREEN (-3475 2150);
DISPLAY INVISIBLE (-3475 2150);
FORCEPROP 1 LAST HDL_TAP TRUE
J 0
(-3150 1975);
DISPLAY 0.872340 (-3150 1975);
DISPLAY INVISIBLE (-3150 1975);
FORCEPROP 1 LAST PATH I234
J 0
(-3477 2100);
DISPLAY 0.872340 (-3477 2100);
PAINT GREEN (-3477 2100);
DISPLAY INVISIBLE (-3477 2100);
FORCEADD OFFPAGE..6
R 2
(-2875 2050);
FORCEPROP 2 LAST $XR0 99 
J 0
(-2661 2050);
DISPLAY 0.638298 (-2661 2050);
PAINT MONO (-2661 2050);
FORCEPROP 2 LAST PATH I235
J 0
(-2650 2100);
DISPLAY 1.021277 (-2650 2100);
DISPLAY INVISIBLE (-2650 2100);
FORCEPROP 1 LAST COMMENT_BODY TRUE
J 2
(-2975 1975);
DISPLAY 0.872340 (-2975 1975);
PAINT GREEN (-2975 1975);
DISPLAY INVISIBLE (-2975 1975);
FORCEPROP 1 LAST OFFPAGE TRUE
J 2
(-3200 1925);
DISPLAY 0.872340 (-3200 1925);
PAINT GREEN (-3200 1925);
DISPLAY INVISIBLE (-3200 1925);
FORCEPROP 2 LAST CDS_LIB mstr_standard
J 2
(-2875 2050);
DISPLAY 0.723404 (-2875 2050);
PAINT MONO (-2875 2050);
DISPLAY INVISIBLE (-2875 2050);
FORCEADD TAP..1
(-3475 2000);
FORCEPROP 3 LASTPIN (-3525 2000) SIG_NAME M_C_CPU1_SB_CB<0>
J 0
(-3515 2010);
DISPLAY 0.659574 (-3515 2010);
PAINT MONO (-3515 2010);
DISPLAY INVISIBLE (-3515 2010);
FORCEPROP 1 LASTPIN (-3525 2000) BN 0
J 0
(-3537 2008);
DISPLAY 0.489362 (-3537 2008);
PAINT GREEN (-3537 2008);
FORCEPROP 2 LAST CDS_LIB mstr_standard
J 2
(-3475 2000);
DISPLAY 0.723404 (-3475 2000);
PAINT MONO (-3475 2000);
DISPLAY INVISIBLE (-3475 2000);
FORCEPROP 1 LAST BODY_TYPE PLUMBING
J 0
(-3475 2050);
DISPLAY 0.872340 (-3475 2050);
PAINT GREEN (-3475 2050);
DISPLAY INVISIBLE (-3475 2050);
FORCEPROP 1 LAST HDL_TAP TRUE
J 0
(-3150 1875);
DISPLAY 0.872340 (-3150 1875);
DISPLAY INVISIBLE (-3150 1875);
FORCEPROP 1 LAST PATH I236
J 0
(-3477 2000);
DISPLAY 0.872340 (-3477 2000);
PAINT GREEN (-3477 2000);
DISPLAY INVISIBLE (-3477 2000);
FORCEADD TAP..1
(-3475 1950);
FORCEPROP 3 LASTPIN (-3525 1950) SIG_NAME M_C_CPU1_SB_CB<1>
J 0
(-3515 1960);
DISPLAY 0.659574 (-3515 1960);
PAINT MONO (-3515 1960);
DISPLAY INVISIBLE (-3515 1960);
FORCEPROP 1 LASTPIN (-3525 1950) BN 1
J 0
(-3537 1958);
DISPLAY 0.489362 (-3537 1958);
PAINT GREEN (-3537 1958);
FORCEPROP 2 LAST CDS_LIB mstr_standard
J 2
(-3475 1950);
DISPLAY 0.723404 (-3475 1950);
PAINT MONO (-3475 1950);
DISPLAY INVISIBLE (-3475 1950);
FORCEPROP 1 LAST BODY_TYPE PLUMBING
J 0
(-3475 2000);
DISPLAY 0.872340 (-3475 2000);
PAINT GREEN (-3475 2000);
DISPLAY INVISIBLE (-3475 2000);
FORCEPROP 1 LAST HDL_TAP TRUE
J 0
(-3150 1825);
DISPLAY 0.872340 (-3150 1825);
DISPLAY INVISIBLE (-3150 1825);
FORCEPROP 1 LAST PATH I237
J 0
(-3477 1950);
DISPLAY 0.872340 (-3477 1950);
PAINT GREEN (-3477 1950);
DISPLAY INVISIBLE (-3477 1950);
FORCEADD TAP..1
(-3475 1900);
FORCEPROP 3 LASTPIN (-3525 1900) SIG_NAME M_C_CPU1_SB_CB<2>
J 0
(-3515 1910);
DISPLAY 0.659574 (-3515 1910);
PAINT MONO (-3515 1910);
DISPLAY INVISIBLE (-3515 1910);
FORCEPROP 1 LASTPIN (-3525 1900) BN 2
J 0
(-3537 1908);
DISPLAY 0.489362 (-3537 1908);
PAINT GREEN (-3537 1908);
FORCEPROP 2 LAST CDS_LIB mstr_standard
J 2
(-3475 1900);
DISPLAY 0.723404 (-3475 1900);
PAINT MONO (-3475 1900);
DISPLAY INVISIBLE (-3475 1900);
FORCEPROP 1 LAST BODY_TYPE PLUMBING
J 0
(-3475 1950);
DISPLAY 0.872340 (-3475 1950);
PAINT GREEN (-3475 1950);
DISPLAY INVISIBLE (-3475 1950);
FORCEPROP 1 LAST HDL_TAP TRUE
J 0
(-3150 1775);
DISPLAY 0.872340 (-3150 1775);
DISPLAY INVISIBLE (-3150 1775);
FORCEPROP 1 LAST PATH I238
J 0
(-3477 1900);
DISPLAY 0.872340 (-3477 1900);
PAINT GREEN (-3477 1900);
DISPLAY INVISIBLE (-3477 1900);
FORCEADD TAP..1
(-3475 1850);
FORCEPROP 3 LASTPIN (-3525 1850) SIG_NAME M_C_CPU1_SB_CB<3>
J 0
(-3515 1860);
DISPLAY 0.659574 (-3515 1860);
PAINT MONO (-3515 1860);
DISPLAY INVISIBLE (-3515 1860);
FORCEPROP 1 LASTPIN (-3525 1850) BN 3
J 0
(-3537 1858);
DISPLAY 0.489362 (-3537 1858);
PAINT GREEN (-3537 1858);
FORCEPROP 2 LAST CDS_LIB mstr_standard
J 2
(-3475 1850);
DISPLAY 0.723404 (-3475 1850);
PAINT MONO (-3475 1850);
DISPLAY INVISIBLE (-3475 1850);
FORCEPROP 1 LAST BODY_TYPE PLUMBING
J 0
(-3475 1900);
DISPLAY 0.872340 (-3475 1900);
PAINT GREEN (-3475 1900);
DISPLAY INVISIBLE (-3475 1900);
FORCEPROP 1 LAST HDL_TAP TRUE
J 0
(-3150 1725);
DISPLAY 0.872340 (-3150 1725);
DISPLAY INVISIBLE (-3150 1725);
FORCEPROP 1 LAST PATH I239
J 0
(-3477 1850);
DISPLAY 0.872340 (-3477 1850);
PAINT GREEN (-3477 1850);
DISPLAY INVISIBLE (-3477 1850);
FORCEADD TAP..1
(-3475 1800);
FORCEPROP 3 LASTPIN (-3525 1800) SIG_NAME M_C_CPU1_SB_CB<4>
J 0
(-3515 1810);
DISPLAY 0.659574 (-3515 1810);
PAINT MONO (-3515 1810);
DISPLAY INVISIBLE (-3515 1810);
FORCEPROP 1 LASTPIN (-3525 1800) BN 4
J 0
(-3537 1808);
DISPLAY 0.489362 (-3537 1808);
PAINT GREEN (-3537 1808);
FORCEPROP 2 LAST CDS_LIB mstr_standard
J 2
(-3475 1800);
DISPLAY 0.723404 (-3475 1800);
PAINT MONO (-3475 1800);
DISPLAY INVISIBLE (-3475 1800);
FORCEPROP 1 LAST BODY_TYPE PLUMBING
J 0
(-3475 1850);
DISPLAY 0.872340 (-3475 1850);
PAINT GREEN (-3475 1850);
DISPLAY INVISIBLE (-3475 1850);
FORCEPROP 1 LAST HDL_TAP TRUE
J 0
(-3150 1675);
DISPLAY 0.872340 (-3150 1675);
DISPLAY INVISIBLE (-3150 1675);
FORCEPROP 1 LAST PATH I240
J 0
(-3477 1800);
DISPLAY 0.872340 (-3477 1800);
PAINT GREEN (-3477 1800);
DISPLAY INVISIBLE (-3477 1800);
FORCEADD TAP..1
(-3475 1750);
FORCEPROP 3 LASTPIN (-3525 1750) SIG_NAME M_C_CPU1_SB_CB<5>
J 0
(-3515 1760);
DISPLAY 0.659574 (-3515 1760);
PAINT MONO (-3515 1760);
DISPLAY INVISIBLE (-3515 1760);
FORCEPROP 1 LASTPIN (-3525 1750) BN 5
J 0
(-3537 1758);
DISPLAY 0.489362 (-3537 1758);
PAINT GREEN (-3537 1758);
FORCEPROP 2 LAST CDS_LIB mstr_standard
J 2
(-3475 1750);
DISPLAY 0.723404 (-3475 1750);
PAINT MONO (-3475 1750);
DISPLAY INVISIBLE (-3475 1750);
FORCEPROP 1 LAST BODY_TYPE PLUMBING
J 0
(-3475 1800);
DISPLAY 0.872340 (-3475 1800);
PAINT GREEN (-3475 1800);
DISPLAY INVISIBLE (-3475 1800);
FORCEPROP 1 LAST HDL_TAP TRUE
J 0
(-3150 1625);
DISPLAY 0.872340 (-3150 1625);
DISPLAY INVISIBLE (-3150 1625);
FORCEPROP 1 LAST PATH I241
J 0
(-3477 1750);
DISPLAY 0.872340 (-3477 1750);
PAINT GREEN (-3477 1750);
DISPLAY INVISIBLE (-3477 1750);
FORCEADD TAP..1
(-3475 1650);
FORCEPROP 3 LASTPIN (-3525 1650) SIG_NAME M_C_CPU1_SB_CB<7>
J 0
(-3515 1660);
DISPLAY 0.659574 (-3515 1660);
PAINT MONO (-3515 1660);
DISPLAY INVISIBLE (-3515 1660);
FORCEPROP 1 LASTPIN (-3525 1650) BN 7
J 0
(-3537 1658);
DISPLAY 0.489362 (-3537 1658);
PAINT GREEN (-3537 1658);
FORCEPROP 2 LAST CDS_LIB mstr_standard
J 2
(-3475 1650);
DISPLAY 0.723404 (-3475 1650);
PAINT MONO (-3475 1650);
DISPLAY INVISIBLE (-3475 1650);
FORCEPROP 1 LAST BODY_TYPE PLUMBING
J 0
(-3475 1700);
DISPLAY 0.872340 (-3475 1700);
PAINT GREEN (-3475 1700);
DISPLAY INVISIBLE (-3475 1700);
FORCEPROP 1 LAST HDL_TAP TRUE
J 0
(-3150 1525);
DISPLAY 0.872340 (-3150 1525);
DISPLAY INVISIBLE (-3150 1525);
FORCEPROP 1 LAST PATH I242
J 0
(-3477 1650);
DISPLAY 0.872340 (-3477 1650);
PAINT GREEN (-3477 1650);
DISPLAY INVISIBLE (-3477 1650);
FORCEADD TAP..1
(-3475 1700);
FORCEPROP 3 LASTPIN (-3525 1700) SIG_NAME M_C_CPU1_SB_CB<6>
J 0
(-3515 1710);
DISPLAY 0.659574 (-3515 1710);
PAINT MONO (-3515 1710);
DISPLAY INVISIBLE (-3515 1710);
FORCEPROP 1 LASTPIN (-3525 1700) BN 6
J 0
(-3537 1708);
DISPLAY 0.489362 (-3537 1708);
PAINT GREEN (-3537 1708);
FORCEPROP 2 LAST CDS_LIB mstr_standard
J 2
(-3475 1700);
DISPLAY 0.723404 (-3475 1700);
PAINT MONO (-3475 1700);
DISPLAY INVISIBLE (-3475 1700);
FORCEPROP 1 LAST BODY_TYPE PLUMBING
J 0
(-3475 1750);
DISPLAY 0.872340 (-3475 1750);
PAINT GREEN (-3475 1750);
DISPLAY INVISIBLE (-3475 1750);
FORCEPROP 1 LAST HDL_TAP TRUE
J 0
(-3150 1575);
DISPLAY 0.872340 (-3150 1575);
DISPLAY INVISIBLE (-3150 1575);
FORCEPROP 1 LAST PATH I243
J 0
(-3477 1700);
DISPLAY 0.872340 (-3477 1700);
PAINT GREEN (-3477 1700);
DISPLAY INVISIBLE (-3477 1700);
FORCEADD TAP..1
R 2
(-5900 6050);
FORCEPROP 3 LASTPIN (-5850 6050) SIG_NAME M_C_CPU1_SA_DQS_DP<0>
J 0
(-5840 6060);
DISPLAY 0.659574 (-5840 6060);
PAINT MONO (-5840 6060);
DISPLAY INVISIBLE (-5840 6060);
FORCEPROP 1 LASTPIN (-5850 6050) BN 0
J 2
(-5838 6058);
DISPLAY 0.489362 (-5838 6058);
PAINT GREEN (-5838 6058);
FORCEPROP 2 LAST CDS_LIB mstr_standard
J 2
(-5900 6050);
DISPLAY 0.723404 (-5900 6050);
PAINT MONO (-5900 6050);
DISPLAY INVISIBLE (-5900 6050);
FORCEPROP 1 LAST BODY_TYPE PLUMBING
J 2
(-5900 6100);
DISPLAY 0.872340 (-5900 6100);
PAINT GREEN (-5900 6100);
DISPLAY INVISIBLE (-5900 6100);
FORCEPROP 1 LAST HDL_TAP TRUE
J 2
(-6225 5925);
DISPLAY 0.872340 (-6225 5925);
DISPLAY INVISIBLE (-6225 5925);
FORCEPROP 1 LAST PATH I244
J 2
(-5898 6050);
DISPLAY 0.872340 (-5898 6050);
PAINT GREEN (-5898 6050);
DISPLAY INVISIBLE (-5898 6050);
FORCEADD TAP..1
R 2
(-5900 5950);
FORCEPROP 3 LASTPIN (-5850 5950) SIG_NAME M_C_CPU1_SA_DQS_DP<1>
J 0
(-5840 5960);
DISPLAY 0.659574 (-5840 5960);
PAINT MONO (-5840 5960);
DISPLAY INVISIBLE (-5840 5960);
FORCEPROP 1 LASTPIN (-5850 5950) BN 1
J 2
(-5838 5958);
DISPLAY 0.489362 (-5838 5958);
PAINT GREEN (-5838 5958);
FORCEPROP 2 LAST CDS_LIB mstr_standard
J 2
(-5900 5950);
DISPLAY 0.723404 (-5900 5950);
PAINT MONO (-5900 5950);
DISPLAY INVISIBLE (-5900 5950);
FORCEPROP 1 LAST BODY_TYPE PLUMBING
J 2
(-5900 6000);
DISPLAY 0.872340 (-5900 6000);
PAINT GREEN (-5900 6000);
DISPLAY INVISIBLE (-5900 6000);
FORCEPROP 1 LAST HDL_TAP TRUE
J 2
(-6225 5825);
DISPLAY 0.872340 (-6225 5825);
DISPLAY INVISIBLE (-6225 5825);
FORCEPROP 1 LAST PATH I245
J 2
(-5898 5950);
DISPLAY 0.872340 (-5898 5950);
PAINT GREEN (-5898 5950);
DISPLAY INVISIBLE (-5898 5950);
FORCEADD TAP..1
R 2
(-5900 5850);
FORCEPROP 3 LASTPIN (-5850 5850) SIG_NAME M_C_CPU1_SA_DQS_DP<2>
J 0
(-5840 5860);
DISPLAY 0.659574 (-5840 5860);
PAINT MONO (-5840 5860);
DISPLAY INVISIBLE (-5840 5860);
FORCEPROP 1 LASTPIN (-5850 5850) BN 2
J 2
(-5838 5858);
DISPLAY 0.489362 (-5838 5858);
PAINT GREEN (-5838 5858);
FORCEPROP 2 LAST CDS_LIB mstr_standard
J 2
(-5900 5850);
DISPLAY 0.723404 (-5900 5850);
PAINT MONO (-5900 5850);
DISPLAY INVISIBLE (-5900 5850);
FORCEPROP 1 LAST BODY_TYPE PLUMBING
J 2
(-5900 5900);
DISPLAY 0.872340 (-5900 5900);
PAINT GREEN (-5900 5900);
DISPLAY INVISIBLE (-5900 5900);
FORCEPROP 1 LAST HDL_TAP TRUE
J 2
(-6225 5725);
DISPLAY 0.872340 (-6225 5725);
DISPLAY INVISIBLE (-6225 5725);
FORCEPROP 1 LAST PATH I246
J 2
(-5898 5850);
DISPLAY 0.872340 (-5898 5850);
PAINT GREEN (-5898 5850);
DISPLAY INVISIBLE (-5898 5850);
FORCEADD TAP..1
R 2
(-5900 5650);
FORCEPROP 3 LASTPIN (-5850 5650) SIG_NAME M_C_CPU1_SA_DQS_DP<4>
J 0
(-5840 5660);
DISPLAY 0.659574 (-5840 5660);
PAINT MONO (-5840 5660);
DISPLAY INVISIBLE (-5840 5660);
FORCEPROP 1 LASTPIN (-5850 5650) BN 4
J 2
(-5838 5658);
DISPLAY 0.489362 (-5838 5658);
PAINT GREEN (-5838 5658);
FORCEPROP 2 LAST CDS_LIB mstr_standard
J 2
(-5900 5650);
DISPLAY 0.723404 (-5900 5650);
PAINT MONO (-5900 5650);
DISPLAY INVISIBLE (-5900 5650);
FORCEPROP 1 LAST BODY_TYPE PLUMBING
J 2
(-5900 5700);
DISPLAY 0.872340 (-5900 5700);
PAINT GREEN (-5900 5700);
DISPLAY INVISIBLE (-5900 5700);
FORCEPROP 1 LAST HDL_TAP TRUE
J 2
(-6225 5525);
DISPLAY 0.872340 (-6225 5525);
DISPLAY INVISIBLE (-6225 5525);
FORCEPROP 1 LAST PATH I247
J 2
(-5898 5650);
DISPLAY 0.872340 (-5898 5650);
PAINT GREEN (-5898 5650);
DISPLAY INVISIBLE (-5898 5650);
FORCEADD TAP..1
R 2
(-5900 5750);
FORCEPROP 3 LASTPIN (-5850 5750) SIG_NAME M_C_CPU1_SA_DQS_DP<3>
J 0
(-5840 5760);
DISPLAY 0.659574 (-5840 5760);
PAINT MONO (-5840 5760);
DISPLAY INVISIBLE (-5840 5760);
FORCEPROP 1 LASTPIN (-5850 5750) BN 3
J 2
(-5838 5758);
DISPLAY 0.489362 (-5838 5758);
PAINT GREEN (-5838 5758);
FORCEPROP 2 LAST CDS_LIB mstr_standard
J 2
(-5900 5750);
DISPLAY 0.723404 (-5900 5750);
PAINT MONO (-5900 5750);
DISPLAY INVISIBLE (-5900 5750);
FORCEPROP 1 LAST BODY_TYPE PLUMBING
J 2
(-5900 5800);
DISPLAY 0.872340 (-5900 5800);
PAINT GREEN (-5900 5800);
DISPLAY INVISIBLE (-5900 5800);
FORCEPROP 1 LAST HDL_TAP TRUE
J 2
(-6225 5625);
DISPLAY 0.872340 (-6225 5625);
DISPLAY INVISIBLE (-6225 5625);
FORCEPROP 1 LAST PATH I248
J 2
(-5898 5750);
DISPLAY 0.872340 (-5898 5750);
PAINT GREEN (-5898 5750);
DISPLAY INVISIBLE (-5898 5750);
FORCEADD TAP..1
R 2
(-6100 5900);
FORCEPROP 3 LASTPIN (-6050 5900) SIG_NAME M_C_CPU1_SA_DQS_DN<1>
J 0
(-6040 5910);
DISPLAY 0.659574 (-6040 5910);
PAINT MONO (-6040 5910);
DISPLAY INVISIBLE (-6040 5910);
FORCEPROP 1 LASTPIN (-6050 5900) BN 1
J 2
(-6038 5908);
DISPLAY 0.489362 (-6038 5908);
PAINT GREEN (-6038 5908);
FORCEPROP 2 LAST CDS_LIB mstr_standard
J 2
(-6100 5900);
DISPLAY 0.723404 (-6100 5900);
PAINT MONO (-6100 5900);
DISPLAY INVISIBLE (-6100 5900);
FORCEPROP 1 LAST BODY_TYPE PLUMBING
J 2
(-6100 5950);
DISPLAY 0.872340 (-6100 5950);
PAINT GREEN (-6100 5950);
DISPLAY INVISIBLE (-6100 5950);
FORCEPROP 1 LAST HDL_TAP TRUE
J 2
(-6425 5775);
DISPLAY 0.872340 (-6425 5775);
DISPLAY INVISIBLE (-6425 5775);
FORCEPROP 1 LAST PATH I249
J 2
(-6098 5900);
DISPLAY 0.872340 (-6098 5900);
PAINT GREEN (-6098 5900);
DISPLAY INVISIBLE (-6098 5900);
FORCEADD TAP..1
R 2
(-6100 6000);
FORCEPROP 3 LASTPIN (-6050 6000) SIG_NAME M_C_CPU1_SA_DQS_DN<0>
J 0
(-6040 6010);
DISPLAY 0.659574 (-6040 6010);
PAINT MONO (-6040 6010);
DISPLAY INVISIBLE (-6040 6010);
FORCEPROP 1 LASTPIN (-6050 6000) BN 0
J 2
(-6038 6008);
DISPLAY 0.489362 (-6038 6008);
PAINT GREEN (-6038 6008);
FORCEPROP 2 LAST CDS_LIB mstr_standard
J 2
(-6100 6000);
DISPLAY 0.723404 (-6100 6000);
PAINT MONO (-6100 6000);
DISPLAY INVISIBLE (-6100 6000);
FORCEPROP 1 LAST BODY_TYPE PLUMBING
J 2
(-6100 6050);
DISPLAY 0.872340 (-6100 6050);
PAINT GREEN (-6100 6050);
DISPLAY INVISIBLE (-6100 6050);
FORCEPROP 1 LAST HDL_TAP TRUE
J 2
(-6425 5875);
DISPLAY 0.872340 (-6425 5875);
DISPLAY INVISIBLE (-6425 5875);
FORCEPROP 1 LAST PATH I250
J 2
(-6098 6000);
DISPLAY 0.872340 (-6098 6000);
PAINT GREEN (-6098 6000);
DISPLAY INVISIBLE (-6098 6000);
FORCEADD TAP..1
R 2
(-6100 5800);
FORCEPROP 3 LASTPIN (-6050 5800) SIG_NAME M_C_CPU1_SA_DQS_DN<2>
J 0
(-6040 5810);
DISPLAY 0.659574 (-6040 5810);
PAINT MONO (-6040 5810);
DISPLAY INVISIBLE (-6040 5810);
FORCEPROP 1 LASTPIN (-6050 5800) BN 2
J 2
(-6038 5808);
DISPLAY 0.489362 (-6038 5808);
PAINT GREEN (-6038 5808);
FORCEPROP 2 LAST CDS_LIB mstr_standard
J 2
(-6100 5800);
DISPLAY 0.723404 (-6100 5800);
PAINT MONO (-6100 5800);
DISPLAY INVISIBLE (-6100 5800);
FORCEPROP 1 LAST BODY_TYPE PLUMBING
J 2
(-6100 5850);
DISPLAY 0.872340 (-6100 5850);
PAINT GREEN (-6100 5850);
DISPLAY INVISIBLE (-6100 5850);
FORCEPROP 1 LAST HDL_TAP TRUE
J 2
(-6425 5675);
DISPLAY 0.872340 (-6425 5675);
DISPLAY INVISIBLE (-6425 5675);
FORCEPROP 1 LAST PATH I251
J 2
(-6098 5800);
DISPLAY 0.872340 (-6098 5800);
PAINT GREEN (-6098 5800);
DISPLAY INVISIBLE (-6098 5800);
FORCEADD TAP..1
R 2
(-6100 5700);
FORCEPROP 3 LASTPIN (-6050 5700) SIG_NAME M_C_CPU1_SA_DQS_DN<3>
J 0
(-6040 5710);
DISPLAY 0.659574 (-6040 5710);
PAINT MONO (-6040 5710);
DISPLAY INVISIBLE (-6040 5710);
FORCEPROP 1 LASTPIN (-6050 5700) BN 3
J 2
(-6038 5708);
DISPLAY 0.489362 (-6038 5708);
PAINT GREEN (-6038 5708);
FORCEPROP 2 LAST CDS_LIB mstr_standard
J 2
(-6100 5700);
DISPLAY 0.723404 (-6100 5700);
PAINT MONO (-6100 5700);
DISPLAY INVISIBLE (-6100 5700);
FORCEPROP 1 LAST BODY_TYPE PLUMBING
J 2
(-6100 5750);
DISPLAY 0.872340 (-6100 5750);
PAINT GREEN (-6100 5750);
DISPLAY INVISIBLE (-6100 5750);
FORCEPROP 1 LAST HDL_TAP TRUE
J 2
(-6425 5575);
DISPLAY 0.872340 (-6425 5575);
DISPLAY INVISIBLE (-6425 5575);
FORCEPROP 1 LAST PATH I252
J 2
(-6098 5700);
DISPLAY 0.872340 (-6098 5700);
PAINT GREEN (-6098 5700);
DISPLAY INVISIBLE (-6098 5700);
FORCEADD TAP..1
R 2
(-5900 5550);
FORCEPROP 3 LASTPIN (-5850 5550) SIG_NAME M_C_CPU1_SA_DQS_DP<5>
J 0
(-5840 5560);
DISPLAY 0.659574 (-5840 5560);
PAINT MONO (-5840 5560);
DISPLAY INVISIBLE (-5840 5560);
FORCEPROP 1 LASTPIN (-5850 5550) BN 5
J 2
(-5838 5558);
DISPLAY 0.489362 (-5838 5558);
PAINT GREEN (-5838 5558);
FORCEPROP 2 LAST CDS_LIB mstr_standard
J 2
(-5900 5550);
DISPLAY 0.723404 (-5900 5550);
PAINT MONO (-5900 5550);
DISPLAY INVISIBLE (-5900 5550);
FORCEPROP 1 LAST BODY_TYPE PLUMBING
J 2
(-5900 5600);
DISPLAY 0.872340 (-5900 5600);
PAINT GREEN (-5900 5600);
DISPLAY INVISIBLE (-5900 5600);
FORCEPROP 1 LAST HDL_TAP TRUE
J 2
(-6225 5425);
DISPLAY 0.872340 (-6225 5425);
DISPLAY INVISIBLE (-6225 5425);
FORCEPROP 1 LAST PATH I253
J 2
(-5898 5550);
DISPLAY 0.872340 (-5898 5550);
PAINT GREEN (-5898 5550);
DISPLAY INVISIBLE (-5898 5550);
FORCEADD TAP..1
R 2
(-5900 5450);
FORCEPROP 3 LASTPIN (-5850 5450) SIG_NAME M_C_CPU1_SA_DQS_DP<6>
J 0
(-5840 5460);
DISPLAY 0.659574 (-5840 5460);
PAINT MONO (-5840 5460);
DISPLAY INVISIBLE (-5840 5460);
FORCEPROP 1 LASTPIN (-5850 5450) BN 6
J 2
(-5838 5458);
DISPLAY 0.489362 (-5838 5458);
PAINT GREEN (-5838 5458);
FORCEPROP 2 LAST CDS_LIB mstr_standard
J 2
(-5900 5450);
DISPLAY 0.723404 (-5900 5450);
PAINT MONO (-5900 5450);
DISPLAY INVISIBLE (-5900 5450);
FORCEPROP 1 LAST BODY_TYPE PLUMBING
J 2
(-5900 5500);
DISPLAY 0.872340 (-5900 5500);
PAINT GREEN (-5900 5500);
DISPLAY INVISIBLE (-5900 5500);
FORCEPROP 1 LAST HDL_TAP TRUE
J 2
(-6225 5325);
DISPLAY 0.872340 (-6225 5325);
DISPLAY INVISIBLE (-6225 5325);
FORCEPROP 1 LAST PATH I254
J 2
(-5898 5450);
DISPLAY 0.872340 (-5898 5450);
PAINT GREEN (-5898 5450);
DISPLAY INVISIBLE (-5898 5450);
FORCEADD TAP..1
R 2
(-5900 5250);
FORCEPROP 3 LASTPIN (-5850 5250) SIG_NAME M_C_CPU1_SA_DQS_DP<8>
J 0
(-5840 5260);
DISPLAY 0.659574 (-5840 5260);
PAINT MONO (-5840 5260);
DISPLAY INVISIBLE (-5840 5260);
FORCEPROP 1 LASTPIN (-5850 5250) BN 8
J 2
(-5838 5258);
DISPLAY 0.489362 (-5838 5258);
PAINT GREEN (-5838 5258);
FORCEPROP 2 LAST CDS_LIB mstr_standard
J 2
(-5900 5250);
DISPLAY 0.723404 (-5900 5250);
PAINT MONO (-5900 5250);
DISPLAY INVISIBLE (-5900 5250);
FORCEPROP 1 LAST BODY_TYPE PLUMBING
J 2
(-5900 5300);
DISPLAY 0.872340 (-5900 5300);
PAINT GREEN (-5900 5300);
DISPLAY INVISIBLE (-5900 5300);
FORCEPROP 1 LAST HDL_TAP TRUE
J 2
(-6225 5125);
DISPLAY 0.872340 (-6225 5125);
DISPLAY INVISIBLE (-6225 5125);
FORCEPROP 1 LAST PATH I255
J 2
(-5898 5250);
DISPLAY 0.872340 (-5898 5250);
PAINT GREEN (-5898 5250);
DISPLAY INVISIBLE (-5898 5250);
FORCEADD TAP..1
R 2
(-5900 5350);
FORCEPROP 3 LASTPIN (-5850 5350) SIG_NAME M_C_CPU1_SA_DQS_DP<7>
J 0
(-5840 5360);
DISPLAY 0.659574 (-5840 5360);
PAINT MONO (-5840 5360);
DISPLAY INVISIBLE (-5840 5360);
FORCEPROP 1 LASTPIN (-5850 5350) BN 7
J 2
(-5838 5358);
DISPLAY 0.489362 (-5838 5358);
PAINT GREEN (-5838 5358);
FORCEPROP 2 LAST CDS_LIB mstr_standard
J 2
(-5900 5350);
DISPLAY 0.723404 (-5900 5350);
PAINT MONO (-5900 5350);
DISPLAY INVISIBLE (-5900 5350);
FORCEPROP 1 LAST BODY_TYPE PLUMBING
J 2
(-5900 5400);
DISPLAY 0.872340 (-5900 5400);
PAINT GREEN (-5900 5400);
DISPLAY INVISIBLE (-5900 5400);
FORCEPROP 1 LAST HDL_TAP TRUE
J 2
(-6225 5225);
DISPLAY 0.872340 (-6225 5225);
DISPLAY INVISIBLE (-6225 5225);
FORCEPROP 1 LAST PATH I256
J 2
(-5898 5350);
DISPLAY 0.872340 (-5898 5350);
PAINT GREEN (-5898 5350);
DISPLAY INVISIBLE (-5898 5350);
FORCEADD TAP..1
R 2
(-5900 5150);
FORCEPROP 3 LASTPIN (-5850 5150) SIG_NAME M_C_CPU1_SA_DQS_DP<9>
J 0
(-5840 5160);
DISPLAY 0.659574 (-5840 5160);
PAINT MONO (-5840 5160);
DISPLAY INVISIBLE (-5840 5160);
FORCEPROP 1 LASTPIN (-5850 5150) BN 9
J 2
(-5838 5158);
DISPLAY 0.489362 (-5838 5158);
PAINT GREEN (-5838 5158);
FORCEPROP 2 LAST CDS_LIB mstr_standard
J 2
(-5900 5150);
DISPLAY 0.723404 (-5900 5150);
PAINT MONO (-5900 5150);
DISPLAY INVISIBLE (-5900 5150);
FORCEPROP 1 LAST BODY_TYPE PLUMBING
J 2
(-5900 5200);
DISPLAY 0.872340 (-5900 5200);
PAINT GREEN (-5900 5200);
DISPLAY INVISIBLE (-5900 5200);
FORCEPROP 1 LAST HDL_TAP TRUE
J 2
(-6225 5025);
DISPLAY 0.872340 (-6225 5025);
DISPLAY INVISIBLE (-6225 5025);
FORCEPROP 1 LAST PATH I257
J 2
(-5898 5150);
DISPLAY 0.872340 (-5898 5150);
PAINT GREEN (-5898 5150);
DISPLAY INVISIBLE (-5898 5150);
FORCEADD TAP..1
R 2
(-6100 5500);
FORCEPROP 3 LASTPIN (-6050 5500) SIG_NAME M_C_CPU1_SA_DQS_DN<5>
J 0
(-6040 5510);
DISPLAY 0.659574 (-6040 5510);
PAINT MONO (-6040 5510);
DISPLAY INVISIBLE (-6040 5510);
FORCEPROP 1 LASTPIN (-6050 5500) BN 5
J 2
(-6038 5508);
DISPLAY 0.489362 (-6038 5508);
PAINT GREEN (-6038 5508);
FORCEPROP 2 LAST CDS_LIB mstr_standard
J 2
(-6100 5500);
DISPLAY 0.723404 (-6100 5500);
PAINT MONO (-6100 5500);
DISPLAY INVISIBLE (-6100 5500);
FORCEPROP 1 LAST BODY_TYPE PLUMBING
J 2
(-6100 5550);
DISPLAY 0.872340 (-6100 5550);
PAINT GREEN (-6100 5550);
DISPLAY INVISIBLE (-6100 5550);
FORCEPROP 1 LAST HDL_TAP TRUE
J 2
(-6425 5375);
DISPLAY 0.872340 (-6425 5375);
DISPLAY INVISIBLE (-6425 5375);
FORCEPROP 1 LAST PATH I258
J 2
(-6098 5500);
DISPLAY 0.872340 (-6098 5500);
PAINT GREEN (-6098 5500);
DISPLAY INVISIBLE (-6098 5500);
FORCEADD TAP..1
R 2
(-6100 5600);
FORCEPROP 3 LASTPIN (-6050 5600) SIG_NAME M_C_CPU1_SA_DQS_DN<4>
J 0
(-6040 5610);
DISPLAY 0.659574 (-6040 5610);
PAINT MONO (-6040 5610);
DISPLAY INVISIBLE (-6040 5610);
FORCEPROP 1 LASTPIN (-6050 5600) BN 4
J 2
(-6038 5608);
DISPLAY 0.489362 (-6038 5608);
PAINT GREEN (-6038 5608);
FORCEPROP 2 LAST CDS_LIB mstr_standard
J 2
(-6100 5600);
DISPLAY 0.723404 (-6100 5600);
PAINT MONO (-6100 5600);
DISPLAY INVISIBLE (-6100 5600);
FORCEPROP 1 LAST BODY_TYPE PLUMBING
J 2
(-6100 5650);
DISPLAY 0.872340 (-6100 5650);
PAINT GREEN (-6100 5650);
DISPLAY INVISIBLE (-6100 5650);
FORCEPROP 1 LAST HDL_TAP TRUE
J 2
(-6425 5475);
DISPLAY 0.872340 (-6425 5475);
DISPLAY INVISIBLE (-6425 5475);
FORCEPROP 1 LAST PATH I259
J 2
(-6098 5600);
DISPLAY 0.872340 (-6098 5600);
PAINT GREEN (-6098 5600);
DISPLAY INVISIBLE (-6098 5600);
FORCEADD TAP..1
R 2
(-6100 5400);
FORCEPROP 3 LASTPIN (-6050 5400) SIG_NAME M_C_CPU1_SA_DQS_DN<6>
J 0
(-6040 5410);
DISPLAY 0.659574 (-6040 5410);
PAINT MONO (-6040 5410);
DISPLAY INVISIBLE (-6040 5410);
FORCEPROP 1 LASTPIN (-6050 5400) BN 6
J 2
(-6038 5408);
DISPLAY 0.489362 (-6038 5408);
PAINT GREEN (-6038 5408);
FORCEPROP 2 LAST CDS_LIB mstr_standard
J 2
(-6100 5400);
DISPLAY 0.723404 (-6100 5400);
PAINT MONO (-6100 5400);
DISPLAY INVISIBLE (-6100 5400);
FORCEPROP 1 LAST BODY_TYPE PLUMBING
J 2
(-6100 5450);
DISPLAY 0.872340 (-6100 5450);
PAINT GREEN (-6100 5450);
DISPLAY INVISIBLE (-6100 5450);
FORCEPROP 1 LAST HDL_TAP TRUE
J 2
(-6425 5275);
DISPLAY 0.872340 (-6425 5275);
DISPLAY INVISIBLE (-6425 5275);
FORCEPROP 1 LAST PATH I260
J 2
(-6098 5400);
DISPLAY 0.872340 (-6098 5400);
PAINT GREEN (-6098 5400);
DISPLAY INVISIBLE (-6098 5400);
FORCEADD TAP..1
R 2
(-6100 5300);
FORCEPROP 3 LASTPIN (-6050 5300) SIG_NAME M_C_CPU1_SA_DQS_DN<7>
J 0
(-6040 5310);
DISPLAY 0.659574 (-6040 5310);
PAINT MONO (-6040 5310);
DISPLAY INVISIBLE (-6040 5310);
FORCEPROP 1 LASTPIN (-6050 5300) BN 7
J 2
(-6038 5308);
DISPLAY 0.489362 (-6038 5308);
PAINT GREEN (-6038 5308);
FORCEPROP 2 LAST CDS_LIB mstr_standard
J 2
(-6100 5300);
DISPLAY 0.723404 (-6100 5300);
PAINT MONO (-6100 5300);
DISPLAY INVISIBLE (-6100 5300);
FORCEPROP 1 LAST BODY_TYPE PLUMBING
J 2
(-6100 5350);
DISPLAY 0.872340 (-6100 5350);
PAINT GREEN (-6100 5350);
DISPLAY INVISIBLE (-6100 5350);
FORCEPROP 1 LAST HDL_TAP TRUE
J 2
(-6425 5175);
DISPLAY 0.872340 (-6425 5175);
DISPLAY INVISIBLE (-6425 5175);
FORCEPROP 1 LAST PATH I261
J 2
(-6098 5300);
DISPLAY 0.872340 (-6098 5300);
PAINT GREEN (-6098 5300);
DISPLAY INVISIBLE (-6098 5300);
FORCEADD TAP..1
R 2
(-6100 5200);
FORCEPROP 3 LASTPIN (-6050 5200) SIG_NAME M_C_CPU1_SA_DQS_DN<8>
J 0
(-6040 5210);
DISPLAY 0.659574 (-6040 5210);
PAINT MONO (-6040 5210);
DISPLAY INVISIBLE (-6040 5210);
FORCEPROP 1 LASTPIN (-6050 5200) BN 8
J 2
(-6038 5208);
DISPLAY 0.489362 (-6038 5208);
PAINT GREEN (-6038 5208);
FORCEPROP 2 LAST CDS_LIB mstr_standard
J 2
(-6100 5200);
DISPLAY 0.723404 (-6100 5200);
PAINT MONO (-6100 5200);
DISPLAY INVISIBLE (-6100 5200);
FORCEPROP 1 LAST BODY_TYPE PLUMBING
J 2
(-6100 5250);
DISPLAY 0.872340 (-6100 5250);
PAINT GREEN (-6100 5250);
DISPLAY INVISIBLE (-6100 5250);
FORCEPROP 1 LAST HDL_TAP TRUE
J 2
(-6425 5075);
DISPLAY 0.872340 (-6425 5075);
DISPLAY INVISIBLE (-6425 5075);
FORCEPROP 1 LAST PATH I262
J 2
(-6098 5200);
DISPLAY 0.872340 (-6098 5200);
PAINT GREEN (-6098 5200);
DISPLAY INVISIBLE (-6098 5200);
FORCEADD TAP..1
R 2
(-5900 5000);
FORCEPROP 3 LASTPIN (-5850 5000) SIG_NAME M_C_CPU1_SB_DQS_DP<0>
J 0
(-5840 5010);
DISPLAY 0.659574 (-5840 5010);
PAINT MONO (-5840 5010);
DISPLAY INVISIBLE (-5840 5010);
FORCEPROP 1 LASTPIN (-5850 5000) BN 0
J 2
(-5838 5008);
DISPLAY 0.489362 (-5838 5008);
PAINT GREEN (-5838 5008);
FORCEPROP 2 LAST CDS_LIB mstr_standard
J 2
(-5900 5000);
DISPLAY 0.723404 (-5900 5000);
PAINT MONO (-5900 5000);
DISPLAY INVISIBLE (-5900 5000);
FORCEPROP 1 LAST BODY_TYPE PLUMBING
J 2
(-5900 5050);
DISPLAY 0.872340 (-5900 5050);
PAINT GREEN (-5900 5050);
DISPLAY INVISIBLE (-5900 5050);
FORCEPROP 1 LAST HDL_TAP TRUE
J 2
(-6225 4875);
DISPLAY 0.872340 (-6225 4875);
DISPLAY INVISIBLE (-6225 4875);
FORCEPROP 1 LAST PATH I263
J 2
(-5898 5000);
DISPLAY 0.872340 (-5898 5000);
PAINT GREEN (-5898 5000);
DISPLAY INVISIBLE (-5898 5000);
FORCEADD TAP..1
R 2
(-5900 4900);
FORCEPROP 3 LASTPIN (-5850 4900) SIG_NAME M_C_CPU1_SB_DQS_DP<1>
J 0
(-5840 4910);
DISPLAY 0.659574 (-5840 4910);
PAINT MONO (-5840 4910);
DISPLAY INVISIBLE (-5840 4910);
FORCEPROP 1 LASTPIN (-5850 4900) BN 1
J 2
(-5838 4908);
DISPLAY 0.489362 (-5838 4908);
PAINT GREEN (-5838 4908);
FORCEPROP 2 LAST CDS_LIB mstr_standard
J 2
(-5900 4900);
DISPLAY 0.723404 (-5900 4900);
PAINT MONO (-5900 4900);
DISPLAY INVISIBLE (-5900 4900);
FORCEPROP 1 LAST BODY_TYPE PLUMBING
J 2
(-5900 4950);
DISPLAY 0.872340 (-5900 4950);
PAINT GREEN (-5900 4950);
DISPLAY INVISIBLE (-5900 4950);
FORCEPROP 1 LAST HDL_TAP TRUE
J 2
(-6225 4775);
DISPLAY 0.872340 (-6225 4775);
DISPLAY INVISIBLE (-6225 4775);
FORCEPROP 1 LAST PATH I264
J 2
(-5898 4900);
DISPLAY 0.872340 (-5898 4900);
PAINT GREEN (-5898 4900);
DISPLAY INVISIBLE (-5898 4900);
FORCEADD TAP..1
R 2
(-5900 4800);
FORCEPROP 3 LASTPIN (-5850 4800) SIG_NAME M_C_CPU1_SB_DQS_DP<2>
J 0
(-5840 4810);
DISPLAY 0.659574 (-5840 4810);
PAINT MONO (-5840 4810);
DISPLAY INVISIBLE (-5840 4810);
FORCEPROP 1 LASTPIN (-5850 4800) BN 2
J 2
(-5838 4808);
DISPLAY 0.489362 (-5838 4808);
PAINT GREEN (-5838 4808);
FORCEPROP 2 LAST CDS_LIB mstr_standard
J 2
(-5900 4800);
DISPLAY 0.723404 (-5900 4800);
PAINT MONO (-5900 4800);
DISPLAY INVISIBLE (-5900 4800);
FORCEPROP 1 LAST BODY_TYPE PLUMBING
J 2
(-5900 4850);
DISPLAY 0.872340 (-5900 4850);
PAINT GREEN (-5900 4850);
DISPLAY INVISIBLE (-5900 4850);
FORCEPROP 1 LAST HDL_TAP TRUE
J 2
(-6225 4675);
DISPLAY 0.872340 (-6225 4675);
DISPLAY INVISIBLE (-6225 4675);
FORCEPROP 1 LAST PATH I265
J 2
(-5898 4800);
DISPLAY 0.872340 (-5898 4800);
PAINT GREEN (-5898 4800);
DISPLAY INVISIBLE (-5898 4800);
FORCEADD TAP..1
R 2
(-5900 4700);
FORCEPROP 3 LASTPIN (-5850 4700) SIG_NAME M_C_CPU1_SB_DQS_DP<3>
J 0
(-5840 4710);
DISPLAY 0.659574 (-5840 4710);
PAINT MONO (-5840 4710);
DISPLAY INVISIBLE (-5840 4710);
FORCEPROP 1 LASTPIN (-5850 4700) BN 3
J 2
(-5838 4708);
DISPLAY 0.489362 (-5838 4708);
PAINT GREEN (-5838 4708);
FORCEPROP 2 LAST CDS_LIB mstr_standard
J 2
(-5900 4700);
DISPLAY 0.723404 (-5900 4700);
PAINT MONO (-5900 4700);
DISPLAY INVISIBLE (-5900 4700);
FORCEPROP 1 LAST BODY_TYPE PLUMBING
J 2
(-5900 4750);
DISPLAY 0.872340 (-5900 4750);
PAINT GREEN (-5900 4750);
DISPLAY INVISIBLE (-5900 4750);
FORCEPROP 1 LAST HDL_TAP TRUE
J 2
(-6225 4575);
DISPLAY 0.872340 (-6225 4575);
DISPLAY INVISIBLE (-6225 4575);
FORCEPROP 1 LAST PATH I266
J 2
(-5898 4700);
DISPLAY 0.872340 (-5898 4700);
PAINT GREEN (-5898 4700);
DISPLAY INVISIBLE (-5898 4700);
FORCEADD TAP..1
R 2
(-6100 5100);
FORCEPROP 3 LASTPIN (-6050 5100) SIG_NAME M_C_CPU1_SA_DQS_DN<9>
J 0
(-6040 5110);
DISPLAY 0.659574 (-6040 5110);
PAINT MONO (-6040 5110);
DISPLAY INVISIBLE (-6040 5110);
FORCEPROP 1 LASTPIN (-6050 5100) BN 9
J 2
(-6038 5108);
DISPLAY 0.489362 (-6038 5108);
PAINT GREEN (-6038 5108);
FORCEPROP 2 LAST CDS_LIB mstr_standard
J 2
(-6100 5100);
DISPLAY 0.723404 (-6100 5100);
PAINT MONO (-6100 5100);
DISPLAY INVISIBLE (-6100 5100);
FORCEPROP 1 LAST BODY_TYPE PLUMBING
J 2
(-6100 5150);
DISPLAY 0.872340 (-6100 5150);
PAINT GREEN (-6100 5150);
DISPLAY INVISIBLE (-6100 5150);
FORCEPROP 1 LAST HDL_TAP TRUE
J 2
(-6425 4975);
DISPLAY 0.872340 (-6425 4975);
DISPLAY INVISIBLE (-6425 4975);
FORCEPROP 1 LAST PATH I267
J 2
(-6098 5100);
DISPLAY 0.872340 (-6098 5100);
PAINT GREEN (-6098 5100);
DISPLAY INVISIBLE (-6098 5100);
FORCEADD TAP..1
R 2
(-6100 4950);
FORCEPROP 3 LASTPIN (-6050 4950) SIG_NAME M_C_CPU1_SB_DQS_DN<0>
J 0
(-6040 4960);
DISPLAY 0.659574 (-6040 4960);
PAINT MONO (-6040 4960);
DISPLAY INVISIBLE (-6040 4960);
FORCEPROP 1 LASTPIN (-6050 4950) BN 0
J 2
(-6038 4958);
DISPLAY 0.489362 (-6038 4958);
PAINT GREEN (-6038 4958);
FORCEPROP 2 LAST CDS_LIB mstr_standard
J 2
(-6100 4950);
DISPLAY 0.723404 (-6100 4950);
PAINT MONO (-6100 4950);
DISPLAY INVISIBLE (-6100 4950);
FORCEPROP 1 LAST BODY_TYPE PLUMBING
J 2
(-6100 5000);
DISPLAY 0.872340 (-6100 5000);
PAINT GREEN (-6100 5000);
DISPLAY INVISIBLE (-6100 5000);
FORCEPROP 1 LAST HDL_TAP TRUE
J 2
(-6425 4825);
DISPLAY 0.872340 (-6425 4825);
DISPLAY INVISIBLE (-6425 4825);
FORCEPROP 1 LAST PATH I268
J 2
(-6098 4950);
DISPLAY 0.872340 (-6098 4950);
PAINT GREEN (-6098 4950);
DISPLAY INVISIBLE (-6098 4950);
FORCEADD TAP..1
R 2
(-6100 4850);
FORCEPROP 3 LASTPIN (-6050 4850) SIG_NAME M_C_CPU1_SB_DQS_DN<1>
J 0
(-6040 4860);
DISPLAY 0.659574 (-6040 4860);
PAINT MONO (-6040 4860);
DISPLAY INVISIBLE (-6040 4860);
FORCEPROP 1 LASTPIN (-6050 4850) BN 1
J 2
(-6038 4858);
DISPLAY 0.489362 (-6038 4858);
PAINT GREEN (-6038 4858);
FORCEPROP 2 LAST CDS_LIB mstr_standard
J 2
(-6100 4850);
DISPLAY 0.723404 (-6100 4850);
PAINT MONO (-6100 4850);
DISPLAY INVISIBLE (-6100 4850);
FORCEPROP 1 LAST BODY_TYPE PLUMBING
J 2
(-6100 4900);
DISPLAY 0.872340 (-6100 4900);
PAINT GREEN (-6100 4900);
DISPLAY INVISIBLE (-6100 4900);
FORCEPROP 1 LAST HDL_TAP TRUE
J 2
(-6425 4725);
DISPLAY 0.872340 (-6425 4725);
DISPLAY INVISIBLE (-6425 4725);
FORCEPROP 1 LAST PATH I269
J 2
(-6098 4850);
DISPLAY 0.872340 (-6098 4850);
PAINT GREEN (-6098 4850);
DISPLAY INVISIBLE (-6098 4850);
FORCEADD TAP..1
R 2
(-6100 4750);
FORCEPROP 3 LASTPIN (-6050 4750) SIG_NAME M_C_CPU1_SB_DQS_DN<2>
J 0
(-6040 4760);
DISPLAY 0.659574 (-6040 4760);
PAINT MONO (-6040 4760);
DISPLAY INVISIBLE (-6040 4760);
FORCEPROP 1 LASTPIN (-6050 4750) BN 2
J 2
(-6038 4758);
DISPLAY 0.489362 (-6038 4758);
PAINT GREEN (-6038 4758);
FORCEPROP 2 LAST CDS_LIB mstr_standard
J 2
(-6100 4750);
DISPLAY 0.723404 (-6100 4750);
PAINT MONO (-6100 4750);
DISPLAY INVISIBLE (-6100 4750);
FORCEPROP 1 LAST BODY_TYPE PLUMBING
J 2
(-6100 4800);
DISPLAY 0.872340 (-6100 4800);
PAINT GREEN (-6100 4800);
DISPLAY INVISIBLE (-6100 4800);
FORCEPROP 1 LAST HDL_TAP TRUE
J 2
(-6425 4625);
DISPLAY 0.872340 (-6425 4625);
DISPLAY INVISIBLE (-6425 4625);
FORCEPROP 1 LAST PATH I270
J 2
(-6098 4750);
DISPLAY 0.872340 (-6098 4750);
PAINT GREEN (-6098 4750);
DISPLAY INVISIBLE (-6098 4750);
FORCEADD TAP..1
R 2
(-6100 4650);
FORCEPROP 3 LASTPIN (-6050 4650) SIG_NAME M_C_CPU1_SB_DQS_DN<3>
J 0
(-6040 4660);
DISPLAY 0.659574 (-6040 4660);
PAINT MONO (-6040 4660);
DISPLAY INVISIBLE (-6040 4660);
FORCEPROP 1 LASTPIN (-6050 4650) BN 3
J 2
(-6038 4658);
DISPLAY 0.489362 (-6038 4658);
PAINT GREEN (-6038 4658);
FORCEPROP 2 LAST CDS_LIB mstr_standard
J 2
(-6100 4650);
DISPLAY 0.723404 (-6100 4650);
PAINT MONO (-6100 4650);
DISPLAY INVISIBLE (-6100 4650);
FORCEPROP 1 LAST BODY_TYPE PLUMBING
J 2
(-6100 4700);
DISPLAY 0.872340 (-6100 4700);
PAINT GREEN (-6100 4700);
DISPLAY INVISIBLE (-6100 4700);
FORCEPROP 1 LAST HDL_TAP TRUE
J 2
(-6425 4525);
DISPLAY 0.872340 (-6425 4525);
DISPLAY INVISIBLE (-6425 4525);
FORCEPROP 1 LAST PATH I271
J 2
(-6098 4650);
DISPLAY 0.872340 (-6098 4650);
PAINT GREEN (-6098 4650);
DISPLAY INVISIBLE (-6098 4650);
FORCEADD TAP..1
R 2
(-5900 4500);
FORCEPROP 3 LASTPIN (-5850 4500) SIG_NAME M_C_CPU1_SB_DQS_DP<5>
J 0
(-5840 4510);
DISPLAY 0.659574 (-5840 4510);
PAINT MONO (-5840 4510);
DISPLAY INVISIBLE (-5840 4510);
FORCEPROP 1 LASTPIN (-5850 4500) BN 5
J 2
(-5838 4508);
DISPLAY 0.489362 (-5838 4508);
PAINT GREEN (-5838 4508);
FORCEPROP 2 LAST CDS_LIB mstr_standard
J 2
(-5900 4500);
DISPLAY 0.723404 (-5900 4500);
PAINT MONO (-5900 4500);
DISPLAY INVISIBLE (-5900 4500);
FORCEPROP 1 LAST BODY_TYPE PLUMBING
J 2
(-5900 4550);
DISPLAY 0.872340 (-5900 4550);
PAINT GREEN (-5900 4550);
DISPLAY INVISIBLE (-5900 4550);
FORCEPROP 1 LAST HDL_TAP TRUE
J 2
(-6225 4375);
DISPLAY 0.872340 (-6225 4375);
DISPLAY INVISIBLE (-6225 4375);
FORCEPROP 1 LAST PATH I272
J 2
(-5898 4500);
DISPLAY 0.872340 (-5898 4500);
PAINT GREEN (-5898 4500);
DISPLAY INVISIBLE (-5898 4500);
FORCEADD TAP..1
R 2
(-5900 4600);
FORCEPROP 3 LASTPIN (-5850 4600) SIG_NAME M_C_CPU1_SB_DQS_DP<4>
J 0
(-5840 4610);
DISPLAY 0.659574 (-5840 4610);
PAINT MONO (-5840 4610);
DISPLAY INVISIBLE (-5840 4610);
FORCEPROP 1 LASTPIN (-5850 4600) BN 4
J 2
(-5838 4608);
DISPLAY 0.489362 (-5838 4608);
PAINT GREEN (-5838 4608);
FORCEPROP 2 LAST CDS_LIB mstr_standard
J 2
(-5900 4600);
DISPLAY 0.723404 (-5900 4600);
PAINT MONO (-5900 4600);
DISPLAY INVISIBLE (-5900 4600);
FORCEPROP 1 LAST BODY_TYPE PLUMBING
J 2
(-5900 4650);
DISPLAY 0.872340 (-5900 4650);
PAINT GREEN (-5900 4650);
DISPLAY INVISIBLE (-5900 4650);
FORCEPROP 1 LAST HDL_TAP TRUE
J 2
(-6225 4475);
DISPLAY 0.872340 (-6225 4475);
DISPLAY INVISIBLE (-6225 4475);
FORCEPROP 1 LAST PATH I273
J 2
(-5898 4600);
DISPLAY 0.872340 (-5898 4600);
PAINT GREEN (-5898 4600);
DISPLAY INVISIBLE (-5898 4600);
FORCEADD TAP..1
R 2
(-5900 4400);
FORCEPROP 3 LASTPIN (-5850 4400) SIG_NAME M_C_CPU1_SB_DQS_DP<6>
J 0
(-5840 4410);
DISPLAY 0.659574 (-5840 4410);
PAINT MONO (-5840 4410);
DISPLAY INVISIBLE (-5840 4410);
FORCEPROP 1 LASTPIN (-5850 4400) BN 6
J 2
(-5838 4408);
DISPLAY 0.489362 (-5838 4408);
PAINT GREEN (-5838 4408);
FORCEPROP 2 LAST CDS_LIB mstr_standard
J 2
(-5900 4400);
DISPLAY 0.723404 (-5900 4400);
PAINT MONO (-5900 4400);
DISPLAY INVISIBLE (-5900 4400);
FORCEPROP 1 LAST BODY_TYPE PLUMBING
J 2
(-5900 4450);
DISPLAY 0.872340 (-5900 4450);
PAINT GREEN (-5900 4450);
DISPLAY INVISIBLE (-5900 4450);
FORCEPROP 1 LAST HDL_TAP TRUE
J 2
(-6225 4275);
DISPLAY 0.872340 (-6225 4275);
DISPLAY INVISIBLE (-6225 4275);
FORCEPROP 1 LAST PATH I274
J 2
(-5898 4400);
DISPLAY 0.872340 (-5898 4400);
PAINT GREEN (-5898 4400);
DISPLAY INVISIBLE (-5898 4400);
FORCEADD TAP..1
R 2
(-5900 4300);
FORCEPROP 3 LASTPIN (-5850 4300) SIG_NAME M_C_CPU1_SB_DQS_DP<7>
J 0
(-5840 4310);
DISPLAY 0.659574 (-5840 4310);
PAINT MONO (-5840 4310);
DISPLAY INVISIBLE (-5840 4310);
FORCEPROP 1 LASTPIN (-5850 4300) BN 7
J 2
(-5838 4308);
DISPLAY 0.489362 (-5838 4308);
PAINT GREEN (-5838 4308);
FORCEPROP 2 LAST CDS_LIB mstr_standard
J 2
(-5900 4300);
DISPLAY 0.723404 (-5900 4300);
PAINT MONO (-5900 4300);
DISPLAY INVISIBLE (-5900 4300);
FORCEPROP 1 LAST BODY_TYPE PLUMBING
J 2
(-5900 4350);
DISPLAY 0.872340 (-5900 4350);
PAINT GREEN (-5900 4350);
DISPLAY INVISIBLE (-5900 4350);
FORCEPROP 1 LAST HDL_TAP TRUE
J 2
(-6225 4175);
DISPLAY 0.872340 (-6225 4175);
DISPLAY INVISIBLE (-6225 4175);
FORCEPROP 1 LAST PATH I275
J 2
(-5898 4300);
DISPLAY 0.872340 (-5898 4300);
PAINT GREEN (-5898 4300);
DISPLAY INVISIBLE (-5898 4300);
FORCEADD TAP..1
R 2
(-5900 4100);
FORCEPROP 3 LASTPIN (-5850 4100) SIG_NAME M_C_CPU1_SB_DQS_DP<9>
J 0
(-5840 4110);
DISPLAY 0.659574 (-5840 4110);
PAINT MONO (-5840 4110);
DISPLAY INVISIBLE (-5840 4110);
FORCEPROP 1 LASTPIN (-5850 4100) BN 9
J 2
(-5838 4108);
DISPLAY 0.489362 (-5838 4108);
PAINT GREEN (-5838 4108);
FORCEPROP 2 LAST CDS_LIB mstr_standard
J 2
(-5900 4100);
DISPLAY 0.723404 (-5900 4100);
PAINT MONO (-5900 4100);
DISPLAY INVISIBLE (-5900 4100);
FORCEPROP 1 LAST BODY_TYPE PLUMBING
J 2
(-5900 4150);
DISPLAY 0.872340 (-5900 4150);
PAINT GREEN (-5900 4150);
DISPLAY INVISIBLE (-5900 4150);
FORCEPROP 1 LAST HDL_TAP TRUE
J 2
(-6225 3975);
DISPLAY 0.872340 (-6225 3975);
DISPLAY INVISIBLE (-6225 3975);
FORCEPROP 1 LAST PATH I276
J 2
(-5898 4100);
DISPLAY 0.872340 (-5898 4100);
PAINT GREEN (-5898 4100);
DISPLAY INVISIBLE (-5898 4100);
FORCEADD TAP..1
R 2
(-5900 4200);
FORCEPROP 3 LASTPIN (-5850 4200) SIG_NAME M_C_CPU1_SB_DQS_DP<8>
J 0
(-5840 4210);
DISPLAY 0.659574 (-5840 4210);
PAINT MONO (-5840 4210);
DISPLAY INVISIBLE (-5840 4210);
FORCEPROP 1 LASTPIN (-5850 4200) BN 8
J 2
(-5838 4208);
DISPLAY 0.489362 (-5838 4208);
PAINT GREEN (-5838 4208);
FORCEPROP 2 LAST CDS_LIB mstr_standard
J 2
(-5900 4200);
DISPLAY 0.723404 (-5900 4200);
PAINT MONO (-5900 4200);
DISPLAY INVISIBLE (-5900 4200);
FORCEPROP 1 LAST BODY_TYPE PLUMBING
J 2
(-5900 4250);
DISPLAY 0.872340 (-5900 4250);
PAINT GREEN (-5900 4250);
DISPLAY INVISIBLE (-5900 4250);
FORCEPROP 1 LAST HDL_TAP TRUE
J 2
(-6225 4075);
DISPLAY 0.872340 (-6225 4075);
DISPLAY INVISIBLE (-6225 4075);
FORCEPROP 1 LAST PATH I277
J 2
(-5898 4200);
DISPLAY 0.872340 (-5898 4200);
PAINT GREEN (-5898 4200);
DISPLAY INVISIBLE (-5898 4200);
FORCEADD TAP..1
R 2
(-6100 4450);
FORCEPROP 3 LASTPIN (-6050 4450) SIG_NAME M_C_CPU1_SB_DQS_DN<5>
J 0
(-6040 4460);
DISPLAY 0.659574 (-6040 4460);
PAINT MONO (-6040 4460);
DISPLAY INVISIBLE (-6040 4460);
FORCEPROP 1 LASTPIN (-6050 4450) BN 5
J 2
(-6038 4458);
DISPLAY 0.489362 (-6038 4458);
PAINT GREEN (-6038 4458);
FORCEPROP 2 LAST CDS_LIB mstr_standard
J 2
(-6100 4450);
DISPLAY 0.723404 (-6100 4450);
PAINT MONO (-6100 4450);
DISPLAY INVISIBLE (-6100 4450);
FORCEPROP 1 LAST BODY_TYPE PLUMBING
J 2
(-6100 4500);
DISPLAY 0.872340 (-6100 4500);
PAINT GREEN (-6100 4500);
DISPLAY INVISIBLE (-6100 4500);
FORCEPROP 1 LAST HDL_TAP TRUE
J 2
(-6425 4325);
DISPLAY 0.872340 (-6425 4325);
DISPLAY INVISIBLE (-6425 4325);
FORCEPROP 1 LAST PATH I278
J 2
(-6098 4450);
DISPLAY 0.872340 (-6098 4450);
PAINT GREEN (-6098 4450);
DISPLAY INVISIBLE (-6098 4450);
FORCEADD TAP..1
R 2
(-6100 4550);
FORCEPROP 3 LASTPIN (-6050 4550) SIG_NAME M_C_CPU1_SB_DQS_DN<4>
J 0
(-6040 4560);
DISPLAY 0.659574 (-6040 4560);
PAINT MONO (-6040 4560);
DISPLAY INVISIBLE (-6040 4560);
FORCEPROP 1 LASTPIN (-6050 4550) BN 4
J 2
(-6038 4558);
DISPLAY 0.489362 (-6038 4558);
PAINT GREEN (-6038 4558);
FORCEPROP 2 LAST CDS_LIB mstr_standard
J 2
(-6100 4550);
DISPLAY 0.723404 (-6100 4550);
PAINT MONO (-6100 4550);
DISPLAY INVISIBLE (-6100 4550);
FORCEPROP 1 LAST BODY_TYPE PLUMBING
J 2
(-6100 4600);
DISPLAY 0.872340 (-6100 4600);
PAINT GREEN (-6100 4600);
DISPLAY INVISIBLE (-6100 4600);
FORCEPROP 1 LAST HDL_TAP TRUE
J 2
(-6425 4425);
DISPLAY 0.872340 (-6425 4425);
DISPLAY INVISIBLE (-6425 4425);
FORCEPROP 1 LAST PATH I279
J 2
(-6098 4550);
DISPLAY 0.872340 (-6098 4550);
PAINT GREEN (-6098 4550);
DISPLAY INVISIBLE (-6098 4550);
FORCEADD TAP..1
R 2
(-6100 4350);
FORCEPROP 3 LASTPIN (-6050 4350) SIG_NAME M_C_CPU1_SB_DQS_DN<6>
J 0
(-6040 4360);
DISPLAY 0.659574 (-6040 4360);
PAINT MONO (-6040 4360);
DISPLAY INVISIBLE (-6040 4360);
FORCEPROP 1 LASTPIN (-6050 4350) BN 6
J 2
(-6038 4358);
DISPLAY 0.489362 (-6038 4358);
PAINT GREEN (-6038 4358);
FORCEPROP 2 LAST CDS_LIB mstr_standard
J 2
(-6100 4350);
DISPLAY 0.723404 (-6100 4350);
PAINT MONO (-6100 4350);
DISPLAY INVISIBLE (-6100 4350);
FORCEPROP 1 LAST BODY_TYPE PLUMBING
J 2
(-6100 4400);
DISPLAY 0.872340 (-6100 4400);
PAINT GREEN (-6100 4400);
DISPLAY INVISIBLE (-6100 4400);
FORCEPROP 1 LAST HDL_TAP TRUE
J 2
(-6425 4225);
DISPLAY 0.872340 (-6425 4225);
DISPLAY INVISIBLE (-6425 4225);
FORCEPROP 1 LAST PATH I280
J 2
(-6098 4350);
DISPLAY 0.872340 (-6098 4350);
PAINT GREEN (-6098 4350);
DISPLAY INVISIBLE (-6098 4350);
FORCEADD TAP..1
R 2
(-6100 4250);
FORCEPROP 3 LASTPIN (-6050 4250) SIG_NAME M_C_CPU1_SB_DQS_DN<7>
J 0
(-6040 4260);
DISPLAY 0.659574 (-6040 4260);
PAINT MONO (-6040 4260);
DISPLAY INVISIBLE (-6040 4260);
FORCEPROP 1 LASTPIN (-6050 4250) BN 7
J 2
(-6038 4258);
DISPLAY 0.489362 (-6038 4258);
PAINT GREEN (-6038 4258);
FORCEPROP 2 LAST CDS_LIB mstr_standard
J 2
(-6100 4250);
DISPLAY 0.723404 (-6100 4250);
PAINT MONO (-6100 4250);
DISPLAY INVISIBLE (-6100 4250);
FORCEPROP 1 LAST BODY_TYPE PLUMBING
J 2
(-6100 4300);
DISPLAY 0.872340 (-6100 4300);
PAINT GREEN (-6100 4300);
DISPLAY INVISIBLE (-6100 4300);
FORCEPROP 1 LAST HDL_TAP TRUE
J 2
(-6425 4125);
DISPLAY 0.872340 (-6425 4125);
DISPLAY INVISIBLE (-6425 4125);
FORCEPROP 1 LAST PATH I281
J 2
(-6098 4250);
DISPLAY 0.872340 (-6098 4250);
PAINT GREEN (-6098 4250);
DISPLAY INVISIBLE (-6098 4250);
FORCEADD TAP..1
R 2
(-6100 4150);
FORCEPROP 3 LASTPIN (-6050 4150) SIG_NAME M_C_CPU1_SB_DQS_DN<8>
J 0
(-6040 4160);
DISPLAY 0.659574 (-6040 4160);
PAINT MONO (-6040 4160);
DISPLAY INVISIBLE (-6040 4160);
FORCEPROP 1 LASTPIN (-6050 4150) BN 8
J 2
(-6038 4158);
DISPLAY 0.489362 (-6038 4158);
PAINT GREEN (-6038 4158);
FORCEPROP 2 LAST CDS_LIB mstr_standard
J 2
(-6100 4150);
DISPLAY 0.723404 (-6100 4150);
PAINT MONO (-6100 4150);
DISPLAY INVISIBLE (-6100 4150);
FORCEPROP 1 LAST BODY_TYPE PLUMBING
J 2
(-6100 4200);
DISPLAY 0.872340 (-6100 4200);
PAINT GREEN (-6100 4200);
DISPLAY INVISIBLE (-6100 4200);
FORCEPROP 1 LAST HDL_TAP TRUE
J 2
(-6425 4025);
DISPLAY 0.872340 (-6425 4025);
DISPLAY INVISIBLE (-6425 4025);
FORCEPROP 1 LAST PATH I282
J 2
(-6098 4150);
DISPLAY 0.872340 (-6098 4150);
PAINT GREEN (-6098 4150);
DISPLAY INVISIBLE (-6098 4150);
FORCEADD OFFPAGE..3
R 2
(-6800 6025);
FORCEPROP 2 LAST $XR0 99 
J 0
(-7079 6025);
DISPLAY 0.638298 (-7079 6025);
PAINT MONO (-7079 6025);
FORCEPROP 2 LAST PATH I283
J 0
(-7100 6075);
DISPLAY 1.021277 (-7100 6075);
DISPLAY INVISIBLE (-7100 6075);
FORCEPROP 1 LAST COMMENT_BODY TRUE
J 2
(-6750 5925);
DISPLAY 0.872340 (-6750 5925);
PAINT GREEN (-6750 5925);
DISPLAY INVISIBLE (-6750 5925);
FORCEPROP 1 LAST OFFPAGE TRUE
J 2
(-7125 5900);
DISPLAY 0.872340 (-7125 5900);
PAINT GREEN (-7125 5900);
DISPLAY INVISIBLE (-7125 5900);
FORCEPROP 2 LAST CDS_LIB standard
J 0
(-6800 6025);
DISPLAY INVISIBLE (-6800 6025);
FORCEADD OFFPAGE..3
R 2
(-6800 6075);
FORCEPROP 2 LAST $XR0 99 
J 0
(-7079 6075);
DISPLAY 0.638298 (-7079 6075);
PAINT MONO (-7079 6075);
FORCEPROP 2 LAST PATH I284
J 0
(-7100 6125);
DISPLAY 1.021277 (-7100 6125);
DISPLAY INVISIBLE (-7100 6125);
FORCEPROP 1 LAST COMMENT_BODY TRUE
J 2
(-6750 5975);
DISPLAY 0.872340 (-6750 5975);
PAINT GREEN (-6750 5975);
DISPLAY INVISIBLE (-6750 5975);
FORCEPROP 1 LAST OFFPAGE TRUE
J 2
(-7125 5950);
DISPLAY 0.872340 (-7125 5950);
PAINT GREEN (-7125 5950);
DISPLAY INVISIBLE (-7125 5950);
FORCEPROP 2 LAST CDS_LIB standard
J 0
(-6800 6075);
DISPLAY INVISIBLE (-6800 6075);
FORCEADD OFFPAGE..3
R 2
(-6800 4975);
FORCEPROP 2 LAST $XR0 99 
J 0
(-7079 4975);
DISPLAY 0.638298 (-7079 4975);
PAINT MONO (-7079 4975);
FORCEPROP 2 LAST PATH I285
J 0
(-7100 5025);
DISPLAY 1.021277 (-7100 5025);
DISPLAY INVISIBLE (-7100 5025);
FORCEPROP 1 LAST COMMENT_BODY TRUE
J 2
(-6750 4875);
DISPLAY 0.872340 (-6750 4875);
PAINT GREEN (-6750 4875);
DISPLAY INVISIBLE (-6750 4875);
FORCEPROP 1 LAST OFFPAGE TRUE
J 2
(-7125 4850);
DISPLAY 0.872340 (-7125 4850);
PAINT GREEN (-7125 4850);
DISPLAY INVISIBLE (-7125 4850);
FORCEPROP 2 LAST CDS_LIB standard
J 0
(-6800 4975);
DISPLAY INVISIBLE (-6800 4975);
FORCEADD OFFPAGE..3
R 2
(-6800 5025);
FORCEPROP 2 LAST $XR0 99 
J 0
(-7079 5025);
DISPLAY 0.638298 (-7079 5025);
PAINT MONO (-7079 5025);
FORCEPROP 2 LAST PATH I286
J 0
(-7100 5075);
DISPLAY 1.021277 (-7100 5075);
DISPLAY INVISIBLE (-7100 5075);
FORCEPROP 1 LAST COMMENT_BODY TRUE
J 2
(-6750 4925);
DISPLAY 0.872340 (-6750 4925);
PAINT GREEN (-6750 4925);
DISPLAY INVISIBLE (-6750 4925);
FORCEPROP 1 LAST OFFPAGE TRUE
J 2
(-7125 4900);
DISPLAY 0.872340 (-7125 4900);
PAINT GREEN (-7125 4900);
DISPLAY INVISIBLE (-7125 4900);
FORCEPROP 2 LAST CDS_LIB standard
J 0
(-6800 5025);
DISPLAY INVISIBLE (-6800 5025);
FORCEADD TAP..1
R 2
(-6100 4050);
FORCEPROP 3 LASTPIN (-6050 4050) SIG_NAME M_C_CPU1_SB_DQS_DN<9>
J 0
(-6040 4060);
DISPLAY 0.659574 (-6040 4060);
PAINT MONO (-6040 4060);
DISPLAY INVISIBLE (-6040 4060);
FORCEPROP 1 LASTPIN (-6050 4050) BN 9
J 2
(-6038 4058);
DISPLAY 0.489362 (-6038 4058);
PAINT GREEN (-6038 4058);
FORCEPROP 2 LAST CDS_LIB mstr_standard
J 2
(-6100 4050);
DISPLAY 0.723404 (-6100 4050);
PAINT MONO (-6100 4050);
DISPLAY INVISIBLE (-6100 4050);
FORCEPROP 1 LAST BODY_TYPE PLUMBING
J 2
(-6100 4100);
DISPLAY 0.872340 (-6100 4100);
PAINT GREEN (-6100 4100);
DISPLAY INVISIBLE (-6100 4100);
FORCEPROP 1 LAST HDL_TAP TRUE
J 2
(-6425 3925);
DISPLAY 0.872340 (-6425 3925);
DISPLAY INVISIBLE (-6425 3925);
FORCEPROP 1 LAST PATH I287
J 2
(-6098 4050);
DISPLAY 0.872340 (-6098 4050);
PAINT GREEN (-6098 4050);
DISPLAY INVISIBLE (-6098 4050);
FORCEADD TAP..1
R 2
(-6100 3850);
FORCEPROP 3 LASTPIN (-6050 3850) SIG_NAME M_C_CPU1_SA_CA<1>
J 0
(-6040 3860);
DISPLAY 0.659574 (-6040 3860);
PAINT MONO (-6040 3860);
DISPLAY INVISIBLE (-6040 3860);
FORCEPROP 1 LASTPIN (-6050 3850) BN 1
J 2
(-6038 3858);
DISPLAY 0.489362 (-6038 3858);
PAINT GREEN (-6038 3858);
FORCEPROP 2 LAST CDS_LIB mstr_standard
J 0
(-6100 3850);
DISPLAY 0.723404 (-6100 3850);
PAINT MONO (-6100 3850);
DISPLAY INVISIBLE (-6100 3850);
FORCEPROP 1 LAST BODY_TYPE PLUMBING
J 2
(-6100 3900);
DISPLAY 0.872340 (-6100 3900);
PAINT GREEN (-6100 3900);
DISPLAY INVISIBLE (-6100 3900);
FORCEPROP 1 LAST HDL_TAP TRUE
J 2
(-6425 3725);
DISPLAY 0.872340 (-6425 3725);
DISPLAY INVISIBLE (-6425 3725);
FORCEPROP 1 LAST PATH I288
J 2
(-6098 3850);
DISPLAY 0.872340 (-6098 3850);
PAINT GREEN (-6098 3850);
DISPLAY INVISIBLE (-6098 3850);
FORCEADD TAP..1
R 2
(-6100 3900);
FORCEPROP 3 LASTPIN (-6050 3900) SIG_NAME M_C_CPU1_SA_CA<0>
J 0
(-6040 3910);
DISPLAY 0.659574 (-6040 3910);
PAINT MONO (-6040 3910);
DISPLAY INVISIBLE (-6040 3910);
FORCEPROP 1 LASTPIN (-6050 3900) BN 0
J 2
(-6038 3908);
DISPLAY 0.489362 (-6038 3908);
PAINT GREEN (-6038 3908);
FORCEPROP 2 LAST CDS_LIB mstr_standard
J 0
(-6100 3900);
DISPLAY 0.723404 (-6100 3900);
PAINT MONO (-6100 3900);
DISPLAY INVISIBLE (-6100 3900);
FORCEPROP 1 LAST BODY_TYPE PLUMBING
J 2
(-6100 3950);
DISPLAY 0.872340 (-6100 3950);
PAINT GREEN (-6100 3950);
DISPLAY INVISIBLE (-6100 3950);
FORCEPROP 1 LAST HDL_TAP TRUE
J 2
(-6425 3775);
DISPLAY 0.872340 (-6425 3775);
DISPLAY INVISIBLE (-6425 3775);
FORCEPROP 1 LAST PATH I289
J 2
(-6098 3900);
DISPLAY 0.872340 (-6098 3900);
PAINT GREEN (-6098 3900);
DISPLAY INVISIBLE (-6098 3900);
FORCEADD TAP..1
R 2
(-6100 3750);
FORCEPROP 3 LASTPIN (-6050 3750) SIG_NAME M_C_CPU1_SA_CA<3>
J 0
(-6040 3760);
DISPLAY 0.659574 (-6040 3760);
PAINT MONO (-6040 3760);
DISPLAY INVISIBLE (-6040 3760);
FORCEPROP 1 LASTPIN (-6050 3750) BN 3
J 2
(-6038 3758);
DISPLAY 0.489362 (-6038 3758);
PAINT GREEN (-6038 3758);
FORCEPROP 2 LAST CDS_LIB mstr_standard
J 0
(-6100 3750);
DISPLAY 0.723404 (-6100 3750);
PAINT MONO (-6100 3750);
DISPLAY INVISIBLE (-6100 3750);
FORCEPROP 1 LAST BODY_TYPE PLUMBING
J 2
(-6100 3800);
DISPLAY 0.872340 (-6100 3800);
PAINT GREEN (-6100 3800);
DISPLAY INVISIBLE (-6100 3800);
FORCEPROP 1 LAST HDL_TAP TRUE
J 2
(-6425 3625);
DISPLAY 0.872340 (-6425 3625);
DISPLAY INVISIBLE (-6425 3625);
FORCEPROP 1 LAST PATH I290
J 2
(-6098 3750);
DISPLAY 0.872340 (-6098 3750);
PAINT GREEN (-6098 3750);
DISPLAY INVISIBLE (-6098 3750);
FORCEADD TAP..1
R 2
(-6100 3800);
FORCEPROP 3 LASTPIN (-6050 3800) SIG_NAME M_C_CPU1_SA_CA<2>
J 0
(-6040 3810);
DISPLAY 0.659574 (-6040 3810);
PAINT MONO (-6040 3810);
DISPLAY INVISIBLE (-6040 3810);
FORCEPROP 1 LASTPIN (-6050 3800) BN 2
J 2
(-6038 3808);
DISPLAY 0.489362 (-6038 3808);
PAINT GREEN (-6038 3808);
FORCEPROP 2 LAST CDS_LIB mstr_standard
J 0
(-6100 3800);
DISPLAY 0.723404 (-6100 3800);
PAINT MONO (-6100 3800);
DISPLAY INVISIBLE (-6100 3800);
FORCEPROP 1 LAST BODY_TYPE PLUMBING
J 2
(-6100 3850);
DISPLAY 0.872340 (-6100 3850);
PAINT GREEN (-6100 3850);
DISPLAY INVISIBLE (-6100 3850);
FORCEPROP 1 LAST HDL_TAP TRUE
J 2
(-6425 3675);
DISPLAY 0.872340 (-6425 3675);
DISPLAY INVISIBLE (-6425 3675);
FORCEPROP 1 LAST PATH I291
J 2
(-6098 3800);
DISPLAY 0.872340 (-6098 3800);
PAINT GREEN (-6098 3800);
DISPLAY INVISIBLE (-6098 3800);
FORCEADD TAP..1
R 2
(-6100 3700);
FORCEPROP 3 LASTPIN (-6050 3700) SIG_NAME M_C_CPU1_SA_CA<4>
J 0
(-6040 3710);
DISPLAY 0.659574 (-6040 3710);
PAINT MONO (-6040 3710);
DISPLAY INVISIBLE (-6040 3710);
FORCEPROP 1 LASTPIN (-6050 3700) BN 4
J 2
(-6038 3708);
DISPLAY 0.489362 (-6038 3708);
PAINT GREEN (-6038 3708);
FORCEPROP 2 LAST CDS_LIB mstr_standard
J 0
(-6100 3700);
DISPLAY 0.723404 (-6100 3700);
PAINT MONO (-6100 3700);
DISPLAY INVISIBLE (-6100 3700);
FORCEPROP 1 LAST BODY_TYPE PLUMBING
J 2
(-6100 3750);
DISPLAY 0.872340 (-6100 3750);
PAINT GREEN (-6100 3750);
DISPLAY INVISIBLE (-6100 3750);
FORCEPROP 1 LAST HDL_TAP TRUE
J 2
(-6425 3575);
DISPLAY 0.872340 (-6425 3575);
DISPLAY INVISIBLE (-6425 3575);
FORCEPROP 1 LAST PATH I292
J 2
(-6098 3700);
DISPLAY 0.872340 (-6098 3700);
PAINT GREEN (-6098 3700);
DISPLAY INVISIBLE (-6098 3700);
FORCEADD TAP..1
R 2
(-6100 3650);
FORCEPROP 3 LASTPIN (-6050 3650) SIG_NAME M_C_CPU1_SA_CA<5>
J 0
(-6040 3660);
DISPLAY 0.659574 (-6040 3660);
PAINT MONO (-6040 3660);
DISPLAY INVISIBLE (-6040 3660);
FORCEPROP 1 LASTPIN (-6050 3650) BN 5
J 2
(-6038 3658);
DISPLAY 0.489362 (-6038 3658);
PAINT GREEN (-6038 3658);
FORCEPROP 2 LAST CDS_LIB mstr_standard
J 0
(-6100 3650);
DISPLAY 0.723404 (-6100 3650);
PAINT MONO (-6100 3650);
DISPLAY INVISIBLE (-6100 3650);
FORCEPROP 1 LAST BODY_TYPE PLUMBING
J 2
(-6100 3700);
DISPLAY 0.872340 (-6100 3700);
PAINT GREEN (-6100 3700);
DISPLAY INVISIBLE (-6100 3700);
FORCEPROP 1 LAST HDL_TAP TRUE
J 2
(-6425 3525);
DISPLAY 0.872340 (-6425 3525);
DISPLAY INVISIBLE (-6425 3525);
FORCEPROP 1 LAST PATH I293
J 2
(-6098 3650);
DISPLAY 0.872340 (-6098 3650);
PAINT GREEN (-6098 3650);
DISPLAY INVISIBLE (-6098 3650);
FORCEADD TAP..1
R 2
(-6100 3600);
FORCEPROP 3 LASTPIN (-6050 3600) SIG_NAME M_C_CPU1_SA_CA<6>
J 0
(-6040 3610);
DISPLAY 0.659574 (-6040 3610);
PAINT MONO (-6040 3610);
DISPLAY INVISIBLE (-6040 3610);
FORCEPROP 1 LASTPIN (-6050 3600) BN 6
J 2
(-6038 3608);
DISPLAY 0.489362 (-6038 3608);
PAINT GREEN (-6038 3608);
FORCEPROP 2 LAST CDS_LIB mstr_standard
J 0
(-6100 3600);
DISPLAY 0.723404 (-6100 3600);
PAINT MONO (-6100 3600);
DISPLAY INVISIBLE (-6100 3600);
FORCEPROP 1 LAST BODY_TYPE PLUMBING
J 2
(-6100 3650);
DISPLAY 0.872340 (-6100 3650);
PAINT GREEN (-6100 3650);
DISPLAY INVISIBLE (-6100 3650);
FORCEPROP 1 LAST HDL_TAP TRUE
J 2
(-6425 3475);
DISPLAY 0.872340 (-6425 3475);
DISPLAY INVISIBLE (-6425 3475);
FORCEPROP 1 LAST PATH I294
J 2
(-6098 3600);
DISPLAY 0.872340 (-6098 3600);
PAINT GREEN (-6098 3600);
DISPLAY INVISIBLE (-6098 3600);
FORCEADD TAP..1
R 2
(-6100 3400);
FORCEPROP 3 LASTPIN (-6050 3400) SIG_NAME M_C_CPU1_SB_CA<2>
J 0
(-6040 3410);
DISPLAY 0.659574 (-6040 3410);
PAINT MONO (-6040 3410);
DISPLAY INVISIBLE (-6040 3410);
FORCEPROP 1 LASTPIN (-6050 3400) BN 2
J 2
(-6038 3408);
DISPLAY 0.489362 (-6038 3408);
PAINT GREEN (-6038 3408);
FORCEPROP 2 LAST CDS_LIB mstr_standard
J 0
(-6100 3400);
DISPLAY 0.723404 (-6100 3400);
PAINT MONO (-6100 3400);
DISPLAY INVISIBLE (-6100 3400);
FORCEPROP 1 LAST BODY_TYPE PLUMBING
J 2
(-6100 3450);
DISPLAY 0.872340 (-6100 3450);
PAINT GREEN (-6100 3450);
DISPLAY INVISIBLE (-6100 3450);
FORCEPROP 1 LAST HDL_TAP TRUE
J 2
(-6425 3275);
DISPLAY 0.872340 (-6425 3275);
DISPLAY INVISIBLE (-6425 3275);
FORCEPROP 1 LAST PATH I295
J 2
(-6098 3400);
DISPLAY 0.872340 (-6098 3400);
PAINT GREEN (-6098 3400);
DISPLAY INVISIBLE (-6098 3400);
FORCEADD TAP..1
R 2
(-6100 3450);
FORCEPROP 3 LASTPIN (-6050 3450) SIG_NAME M_C_CPU1_SB_CA<1>
J 0
(-6040 3460);
DISPLAY 0.659574 (-6040 3460);
PAINT MONO (-6040 3460);
DISPLAY INVISIBLE (-6040 3460);
FORCEPROP 1 LASTPIN (-6050 3450) BN 1
J 2
(-6038 3458);
DISPLAY 0.489362 (-6038 3458);
PAINT GREEN (-6038 3458);
FORCEPROP 2 LAST CDS_LIB mstr_standard
J 0
(-6100 3450);
DISPLAY 0.723404 (-6100 3450);
PAINT MONO (-6100 3450);
DISPLAY INVISIBLE (-6100 3450);
FORCEPROP 1 LAST BODY_TYPE PLUMBING
J 2
(-6100 3500);
DISPLAY 0.872340 (-6100 3500);
PAINT GREEN (-6100 3500);
DISPLAY INVISIBLE (-6100 3500);
FORCEPROP 1 LAST HDL_TAP TRUE
J 2
(-6425 3325);
DISPLAY 0.872340 (-6425 3325);
DISPLAY INVISIBLE (-6425 3325);
FORCEPROP 1 LAST PATH I296
J 2
(-6098 3450);
DISPLAY 0.872340 (-6098 3450);
PAINT GREEN (-6098 3450);
DISPLAY INVISIBLE (-6098 3450);
FORCEADD TAP..1
R 2
(-6100 3500);
FORCEPROP 3 LASTPIN (-6050 3500) SIG_NAME M_C_CPU1_SB_CA<0>
J 0
(-6040 3510);
DISPLAY 0.659574 (-6040 3510);
PAINT MONO (-6040 3510);
DISPLAY INVISIBLE (-6040 3510);
FORCEPROP 1 LASTPIN (-6050 3500) BN 0
J 2
(-6038 3508);
DISPLAY 0.489362 (-6038 3508);
PAINT GREEN (-6038 3508);
FORCEPROP 2 LAST CDS_LIB mstr_standard
J 0
(-6100 3500);
DISPLAY 0.723404 (-6100 3500);
PAINT MONO (-6100 3500);
DISPLAY INVISIBLE (-6100 3500);
FORCEPROP 1 LAST BODY_TYPE PLUMBING
J 2
(-6100 3550);
DISPLAY 0.872340 (-6100 3550);
PAINT GREEN (-6100 3550);
DISPLAY INVISIBLE (-6100 3550);
FORCEPROP 1 LAST HDL_TAP TRUE
J 2
(-6425 3375);
DISPLAY 0.872340 (-6425 3375);
DISPLAY INVISIBLE (-6425 3375);
FORCEPROP 1 LAST PATH I297
J 2
(-6098 3500);
DISPLAY 0.872340 (-6098 3500);
PAINT GREEN (-6098 3500);
DISPLAY INVISIBLE (-6098 3500);
FORCEADD TAP..1
R 2
(-6100 3350);
FORCEPROP 3 LASTPIN (-6050 3350) SIG_NAME M_C_CPU1_SB_CA<3>
J 0
(-6040 3360);
DISPLAY 0.659574 (-6040 3360);
PAINT MONO (-6040 3360);
DISPLAY INVISIBLE (-6040 3360);
FORCEPROP 1 LASTPIN (-6050 3350) BN 3
J 2
(-6038 3358);
DISPLAY 0.489362 (-6038 3358);
PAINT GREEN (-6038 3358);
FORCEPROP 2 LAST CDS_LIB mstr_standard
J 0
(-6100 3350);
DISPLAY 0.723404 (-6100 3350);
PAINT MONO (-6100 3350);
DISPLAY INVISIBLE (-6100 3350);
FORCEPROP 1 LAST BODY_TYPE PLUMBING
J 2
(-6100 3400);
DISPLAY 0.872340 (-6100 3400);
PAINT GREEN (-6100 3400);
DISPLAY INVISIBLE (-6100 3400);
FORCEPROP 1 LAST HDL_TAP TRUE
J 2
(-6425 3225);
DISPLAY 0.872340 (-6425 3225);
DISPLAY INVISIBLE (-6425 3225);
FORCEPROP 1 LAST PATH I298
J 2
(-6098 3350);
DISPLAY 0.872340 (-6098 3350);
PAINT GREEN (-6098 3350);
DISPLAY INVISIBLE (-6098 3350);
FORCEADD TAP..1
R 2
(-6100 3300);
FORCEPROP 3 LASTPIN (-6050 3300) SIG_NAME M_C_CPU1_SB_CA<4>
J 0
(-6040 3310);
DISPLAY 0.659574 (-6040 3310);
PAINT MONO (-6040 3310);
DISPLAY INVISIBLE (-6040 3310);
FORCEPROP 1 LASTPIN (-6050 3300) BN 4
J 2
(-6038 3308);
DISPLAY 0.489362 (-6038 3308);
PAINT GREEN (-6038 3308);
FORCEPROP 2 LAST CDS_LIB mstr_standard
J 0
(-6100 3300);
DISPLAY 0.723404 (-6100 3300);
PAINT MONO (-6100 3300);
DISPLAY INVISIBLE (-6100 3300);
FORCEPROP 1 LAST BODY_TYPE PLUMBING
J 2
(-6100 3350);
DISPLAY 0.872340 (-6100 3350);
PAINT GREEN (-6100 3350);
DISPLAY INVISIBLE (-6100 3350);
FORCEPROP 1 LAST HDL_TAP TRUE
J 2
(-6425 3175);
DISPLAY 0.872340 (-6425 3175);
DISPLAY INVISIBLE (-6425 3175);
FORCEPROP 1 LAST PATH I299
J 2
(-6098 3300);
DISPLAY 0.872340 (-6098 3300);
PAINT GREEN (-6098 3300);
DISPLAY INVISIBLE (-6098 3300);
FORCEADD TAP..1
R 2
(-6100 3250);
FORCEPROP 3 LASTPIN (-6050 3250) SIG_NAME M_C_CPU1_SB_CA<5>
J 0
(-6040 3260);
DISPLAY 0.659574 (-6040 3260);
PAINT MONO (-6040 3260);
DISPLAY INVISIBLE (-6040 3260);
FORCEPROP 1 LASTPIN (-6050 3250) BN 5
J 2
(-6038 3258);
DISPLAY 0.489362 (-6038 3258);
PAINT GREEN (-6038 3258);
FORCEPROP 2 LAST CDS_LIB mstr_standard
J 0
(-6100 3250);
DISPLAY 0.723404 (-6100 3250);
PAINT MONO (-6100 3250);
DISPLAY INVISIBLE (-6100 3250);
FORCEPROP 1 LAST BODY_TYPE PLUMBING
J 2
(-6100 3300);
DISPLAY 0.872340 (-6100 3300);
PAINT GREEN (-6100 3300);
DISPLAY INVISIBLE (-6100 3300);
FORCEPROP 1 LAST HDL_TAP TRUE
J 2
(-6425 3125);
DISPLAY 0.872340 (-6425 3125);
DISPLAY INVISIBLE (-6425 3125);
FORCEPROP 1 LAST PATH I300
J 2
(-6098 3250);
DISPLAY 0.872340 (-6098 3250);
PAINT GREEN (-6098 3250);
DISPLAY INVISIBLE (-6098 3250);
FORCEADD TAP..1
R 2
(-6100 3200);
FORCEPROP 3 LASTPIN (-6050 3200) SIG_NAME M_C_CPU1_SB_CA<6>
J 0
(-6040 3210);
DISPLAY 0.659574 (-6040 3210);
PAINT MONO (-6040 3210);
DISPLAY INVISIBLE (-6040 3210);
FORCEPROP 1 LASTPIN (-6050 3200) BN 6
J 2
(-6038 3208);
DISPLAY 0.489362 (-6038 3208);
PAINT GREEN (-6038 3208);
FORCEPROP 2 LAST CDS_LIB mstr_standard
J 0
(-6100 3200);
DISPLAY 0.723404 (-6100 3200);
PAINT MONO (-6100 3200);
DISPLAY INVISIBLE (-6100 3200);
FORCEPROP 1 LAST BODY_TYPE PLUMBING
J 2
(-6100 3250);
DISPLAY 0.872340 (-6100 3250);
PAINT GREEN (-6100 3250);
DISPLAY INVISIBLE (-6100 3250);
FORCEPROP 1 LAST HDL_TAP TRUE
J 2
(-6425 3075);
DISPLAY 0.872340 (-6425 3075);
DISPLAY INVISIBLE (-6425 3075);
FORCEPROP 1 LAST PATH I301
J 2
(-6098 3200);
DISPLAY 0.872340 (-6098 3200);
PAINT GREEN (-6098 3200);
DISPLAY INVISIBLE (-6098 3200);
FORCEADD OFFPAGE..2
R 2
(-6700 3925);
FORCEPROP 2 LAST $XR0 99 
J 0
(-6954 3925);
DISPLAY 0.638298 (-6954 3925);
PAINT MONO (-6954 3925);
FORCEPROP 2 LAST PATH I302
J 0
(-6975 3975);
DISPLAY 1.021277 (-6975 3975);
DISPLAY INVISIBLE (-6975 3975);
FORCEPROP 1 LAST COMMENT_BODY TRUE
J 2
(-6655 3830);
DISPLAY 0.872340 (-6655 3830);
PAINT GREEN (-6655 3830);
DISPLAY INVISIBLE (-6655 3830);
FORCEPROP 1 LAST OFFPAGE TRUE
J 2
(-7025 3800);
DISPLAY 0.872340 (-7025 3800);
PAINT GREEN (-7025 3800);
DISPLAY INVISIBLE (-7025 3800);
FORCEPROP 2 LAST CDS_LIB standard
J 0
(-6700 3925);
DISPLAY INVISIBLE (-6700 3925);
FORCEADD OFFPAGE..2
R 2
(-6700 3525);
FORCEPROP 2 LAST $XR0 99 
J 0
(-6954 3525);
DISPLAY 0.638298 (-6954 3525);
PAINT MONO (-6954 3525);
FORCEPROP 2 LAST PATH I303
J 0
(-6975 3575);
DISPLAY 1.021277 (-6975 3575);
DISPLAY INVISIBLE (-6975 3575);
FORCEPROP 1 LAST COMMENT_BODY TRUE
J 2
(-6655 3430);
DISPLAY 0.872340 (-6655 3430);
PAINT GREEN (-6655 3430);
DISPLAY INVISIBLE (-6655 3430);
FORCEPROP 1 LAST OFFPAGE TRUE
J 2
(-7025 3400);
DISPLAY 0.872340 (-7025 3400);
PAINT GREEN (-7025 3400);
DISPLAY INVISIBLE (-7025 3400);
FORCEPROP 2 LAST CDS_LIB standard
J 0
(-6700 3525);
DISPLAY INVISIBLE (-6700 3525);
FORCEADD OFFPAGE..2
R 2
(-6700 3000);
FORCEPROP 2 LAST $XR0 99 
J 0
(-6954 3000);
DISPLAY 0.638298 (-6954 3000);
PAINT MONO (-6954 3000);
FORCEPROP 2 LAST PATH I304
J 0
(-6975 3050);
DISPLAY 1.021277 (-6975 3050);
DISPLAY INVISIBLE (-6975 3050);
FORCEPROP 1 LAST COMMENT_BODY TRUE
J 2
(-6655 2905);
DISPLAY 0.872340 (-6655 2905);
PAINT GREEN (-6655 2905);
DISPLAY INVISIBLE (-6655 2905);
FORCEPROP 1 LAST OFFPAGE TRUE
J 2
(-7025 2875);
DISPLAY 0.872340 (-7025 2875);
PAINT GREEN (-7025 2875);
DISPLAY INVISIBLE (-7025 2875);
FORCEPROP 2 LAST CDS_LIB standard
J 0
(-6700 3000);
DISPLAY INVISIBLE (-6700 3000);
FORCEADD OFFPAGE..2
R 2
(-6700 3050);
FORCEPROP 2 LAST $XR0 99 
J 0
(-6954 3050);
DISPLAY 0.638298 (-6954 3050);
PAINT MONO (-6954 3050);
FORCEPROP 2 LAST PATH I305
J 0
(-6975 3100);
DISPLAY 1.021277 (-6975 3100);
DISPLAY INVISIBLE (-6975 3100);
FORCEPROP 1 LAST COMMENT_BODY TRUE
J 2
(-6655 2955);
DISPLAY 0.872340 (-6655 2955);
PAINT GREEN (-6655 2955);
DISPLAY INVISIBLE (-6655 2955);
FORCEPROP 1 LAST OFFPAGE TRUE
J 2
(-7025 2925);
DISPLAY 0.872340 (-7025 2925);
PAINT GREEN (-7025 2925);
DISPLAY INVISIBLE (-7025 2925);
FORCEPROP 2 LAST CDS_LIB standard
J 0
(-6700 3050);
DISPLAY INVISIBLE (-6700 3050);
FORCEADD OFFPAGE..2
R 2
(-6700 2850);
FORCEPROP 2 LAST $XR0 99 
J 0
(-6954 2850);
DISPLAY 0.638298 (-6954 2850);
PAINT MONO (-6954 2850);
FORCEPROP 2 LAST PATH I306
J 0
(-6975 2900);
DISPLAY 1.021277 (-6975 2900);
DISPLAY INVISIBLE (-6975 2900);
FORCEPROP 1 LAST COMMENT_BODY TRUE
J 2
(-6655 2755);
DISPLAY 0.872340 (-6655 2755);
PAINT GREEN (-6655 2755);
DISPLAY INVISIBLE (-6655 2755);
FORCEPROP 1 LAST OFFPAGE TRUE
J 2
(-7025 2725);
DISPLAY 0.872340 (-7025 2725);
PAINT GREEN (-7025 2725);
DISPLAY INVISIBLE (-7025 2725);
FORCEPROP 2 LAST CDS_LIB standard
J 0
(-6700 2850);
DISPLAY INVISIBLE (-6700 2850);
FORCEADD OFFPAGE..2
R 2
(-6700 2900);
FORCEPROP 2 LAST $XR0 99 
J 0
(-6954 2900);
DISPLAY 0.638298 (-6954 2900);
PAINT MONO (-6954 2900);
FORCEPROP 2 LAST PATH I307
J 0
(-6975 2950);
DISPLAY 1.021277 (-6975 2950);
DISPLAY INVISIBLE (-6975 2950);
FORCEPROP 1 LAST COMMENT_BODY TRUE
J 2
(-6655 2805);
DISPLAY 0.872340 (-6655 2805);
PAINT GREEN (-6655 2805);
DISPLAY INVISIBLE (-6655 2805);
FORCEPROP 1 LAST OFFPAGE TRUE
J 2
(-7025 2775);
DISPLAY 0.872340 (-7025 2775);
PAINT GREEN (-7025 2775);
DISPLAY INVISIBLE (-7025 2775);
FORCEPROP 2 LAST CDS_LIB standard
J 0
(-6700 2900);
DISPLAY INVISIBLE (-6700 2900);
FORCEADD OFFPAGE..1
(-6700 2750);
FORCEPROP 2 LAST $XR0 99 
J 0
(-6921 2750);
DISPLAY 0.638298 (-6921 2750);
PAINT MONO (-6921 2750);
FORCEPROP 2 LAST PATH I308
J 0
(-6950 2800);
DISPLAY 1.021277 (-6950 2800);
DISPLAY INVISIBLE (-6950 2800);
FORCEPROP 1 LAST COMMENT_BODY TRUE
J 0
(-6575 2650);
DISPLAY 0.872340 (-6575 2650);
PAINT GREEN (-6575 2650);
DISPLAY INVISIBLE (-6575 2650);
FORCEPROP 1 LAST OFFPAGE TRUE
J 0
(-6375 2625);
DISPLAY 0.872340 (-6375 2625);
PAINT GREEN (-6375 2625);
DISPLAY INVISIBLE (-6375 2625);
FORCEPROP 2 LAST CDS_LIB standard
J 0
(-6700 2750);
DISPLAY INVISIBLE (-6700 2750);
FORCEADD OFFPAGE..5
(-6700 2650);
FORCEPROP 2 LAST $XR0 99 
J 0
(-6954 2650);
DISPLAY 0.638298 (-6954 2650);
PAINT MONO (-6954 2650);
FORCEPROP 2 LAST PATH I309
J 0
(-6975 2700);
DISPLAY 1.021277 (-6975 2700);
DISPLAY INVISIBLE (-6975 2700);
FORCEPROP 1 LAST COMMENT_BODY TRUE
J 0
(-6600 2575);
DISPLAY 0.872340 (-6600 2575);
PAINT GREEN (-6600 2575);
DISPLAY INVISIBLE (-6600 2575);
FORCEPROP 1 LAST OFFPAGE TRUE
J 0
(-6375 2525);
DISPLAY 0.872340 (-6375 2525);
PAINT GREEN (-6375 2525);
DISPLAY INVISIBLE (-6375 2525);
FORCEPROP 2 LAST CDS_LIB mstr_standard
J 0
(-6700 2650);
DISPLAY INVISIBLE (-6700 2650);
FORCEADD OFFPAGE..2
R 2
(-6700 2550);
FORCEPROP 2 LAST $XR0 99 
J 0
(-6954 2550);
DISPLAY 0.638298 (-6954 2550);
PAINT MONO (-6954 2550);
FORCEPROP 2 LAST PATH I310
J 0
(-6975 2600);
DISPLAY 1.021277 (-6975 2600);
DISPLAY INVISIBLE (-6975 2600);
FORCEPROP 1 LAST COMMENT_BODY TRUE
J 2
(-6655 2455);
DISPLAY 0.872340 (-6655 2455);
PAINT GREEN (-6655 2455);
DISPLAY INVISIBLE (-6655 2455);
FORCEPROP 1 LAST OFFPAGE TRUE
J 2
(-7025 2425);
DISPLAY 0.872340 (-7025 2425);
PAINT GREEN (-7025 2425);
DISPLAY INVISIBLE (-7025 2425);
FORCEPROP 2 LAST CDS_LIB standard
J 0
(-6700 2550);
DISPLAY INVISIBLE (-6700 2550);
FORCEADD OFFPAGE..2
R 2
(-6700 2500);
FORCEPROP 2 LAST $XR0 99 
J 0
(-6954 2500);
DISPLAY 0.638298 (-6954 2500);
PAINT MONO (-6954 2500);
FORCEPROP 2 LAST PATH I311
J 0
(-6975 2550);
DISPLAY 1.021277 (-6975 2550);
DISPLAY INVISIBLE (-6975 2550);
FORCEPROP 1 LAST COMMENT_BODY TRUE
J 2
(-6655 2405);
DISPLAY 0.872340 (-6655 2405);
PAINT GREEN (-6655 2405);
DISPLAY INVISIBLE (-6655 2405);
FORCEPROP 1 LAST OFFPAGE TRUE
J 2
(-7025 2375);
DISPLAY 0.872340 (-7025 2375);
PAINT GREEN (-7025 2375);
DISPLAY INVISIBLE (-7025 2375);
FORCEPROP 2 LAST CDS_LIB standard
J 0
(-6700 2500);
DISPLAY INVISIBLE (-6700 2500);
FORCEADD OFFPAGE..1
(-6700 2400);
FORCEPROP 2 LAST $XR0 99 
J 0
(-6921 2400);
DISPLAY 0.638298 (-6921 2400);
PAINT MONO (-6921 2400);
FORCEPROP 2 LAST PATH I312
J 0
(-6950 2450);
DISPLAY 1.021277 (-6950 2450);
DISPLAY INVISIBLE (-6950 2450);
FORCEPROP 1 LAST COMMENT_BODY TRUE
J 0
(-6575 2300);
DISPLAY 0.872340 (-6575 2300);
PAINT GREEN (-6575 2300);
DISPLAY INVISIBLE (-6575 2300);
FORCEPROP 1 LAST OFFPAGE TRUE
J 0
(-6375 2275);
DISPLAY 0.872340 (-6375 2275);
PAINT GREEN (-6375 2275);
DISPLAY INVISIBLE (-6375 2275);
FORCEPROP 2 LAST CDS_LIB standard
J 0
(-6700 2400);
DISPLAY INVISIBLE (-6700 2400);
FORCEADD Q_RES..1
(-6775 2200);
FORCEPROP 1 LAST LOCATION R502
J 0
(-7100 2200);
DISPLAY 0.489362 (-7100 2200);
PAINT SKYBLUE (-7100 2200);
FORCEPROP 0 LAST $SEC 1
J 0
(-6950 2250);
DISPLAY 0.680851 (-6950 2250);
PAINT MONO (-6950 2250);
DISPLAY INVISIBLE (-6950 2250);
FORCEPROP 0 LAST CDS_SEC 1
J 0
(-6950 2250);
DISPLAY 1.021277 (-6950 2250);
DISPLAY INVISIBLE (-6950 2250);
FORCEPROP 1 LASTPIN (-6875 2200) $PN 1
J 0
(-6863 2212);
DISPLAY 0.489362 (-6863 2212);
PAINT MONO (-6863 2212);
FORCEPROP 1 LASTPIN (-6675 2200) $PN 2
J 0
(-6713 2212);
DISPLAY 0.489362 (-6713 2212);
PAINT MONO (-6713 2212);
FORCEPROP 1 LAST TOLERANCE 1%
J 0
(-6500 2200);
DISPLAY 0.489362 (-6500 2200);
PAINT SKYBLUE (-6500 2200);
FORCEPROP 1 LAST VALUE 15   
J 2
(-6450 2200);
DISPLAY 0.489362 (-6450 2200);
PAINT SKYBLUE (-6450 2200);
FORCEPROP 1 LAST PART_NUMBER CS01502FB11
J 0
(-6650 2175);
DISPLAY 0.489362 (-6650 2175);
PAINT SKYBLUE (-6650 2175);
FORCEPROP 1 LAST PACK_TYPE 0402LF
J 0
(-7100 2175);
DISPLAY 0.489362 (-7100 2175);
PAINT SKYBLUE (-7100 2175);
FORCEPROP 2 LAST CDS_LIB pure_quanta
J 0
(-6775 2200);
DISPLAY INVISIBLE (-6775 2200);
FORCEPROP 1 LAST PATH I313
J 0
(-6825 2350);
DISPLAY 0.978723 (-6825 2350);
PAINT WHITE (-6825 2350);
DISPLAY INVISIBLE (-6825 2350);
FORCEPROP 1 LAST WATTAGE 1/16W
J 2
(-6550 2325);
DISPLAY 0.638298 (-6550 2325);
PAINT SKYBLUE (-6550 2325);
DISPLAY INVISIBLE (-6550 2325);
FORCEPROP 1 LAST MATERIAL CHIP
J 0
(-6900 2325);
DISPLAY 0.638298 (-6900 2325);
PAINT SKYBLUE (-6900 2325);
DISPLAY INVISIBLE (-6900 2325);
FORCEADD OFFPAGE..5
(-6700 2300);
FORCEPROP 2 LAST $XR0 99 
J 0
(-6954 2300);
DISPLAY 0.638298 (-6954 2300);
PAINT MONO (-6954 2300);
FORCEPROP 2 LAST PATH I314
J 0
(-6975 2350);
DISPLAY 1.021277 (-6975 2350);
DISPLAY INVISIBLE (-6975 2350);
FORCEPROP 1 LAST COMMENT_BODY TRUE
J 0
(-6600 2225);
DISPLAY 0.872340 (-6600 2225);
PAINT GREEN (-6600 2225);
DISPLAY INVISIBLE (-6600 2225);
FORCEPROP 1 LAST OFFPAGE TRUE
J 0
(-6375 2175);
DISPLAY 0.872340 (-6375 2175);
PAINT GREEN (-6375 2175);
DISPLAY INVISIBLE (-6375 2175);
FORCEPROP 2 LAST CDS_LIB standard
J 0
(-6700 2300);
DISPLAY INVISIBLE (-6700 2300);
FORCEADD OFFPAGE..5
(-6700 2100);
FORCEPROP 2 LAST $XR0 99 
J 0
(-6954 2100);
DISPLAY 0.638298 (-6954 2100);
PAINT MONO (-6954 2100);
FORCEPROP 2 LAST PATH I315
J 0
(-6975 2150);
DISPLAY 1.021277 (-6975 2150);
DISPLAY INVISIBLE (-6975 2150);
FORCEPROP 1 LAST COMMENT_BODY TRUE
J 0
(-6600 2025);
DISPLAY 0.872340 (-6600 2025);
PAINT GREEN (-6600 2025);
DISPLAY INVISIBLE (-6600 2025);
FORCEPROP 1 LAST OFFPAGE TRUE
J 0
(-6375 1975);
DISPLAY 0.872340 (-6375 1975);
PAINT GREEN (-6375 1975);
DISPLAY INVISIBLE (-6375 1975);
FORCEPROP 2 LAST CDS_LIB standard
J 0
(-6700 2100);
DISPLAY INVISIBLE (-6700 2100);
FORCEADD OFFPAGE..1
(-7650 2200);
FORCEPROP 2 LAST $XR0 99 
J 0
(-7871 2200);
DISPLAY 0.638298 (-7871 2200);
PAINT MONO (-7871 2200);
FORCEPROP 2 LAST PATH I316
J 0
(-7900 2250);
DISPLAY 1.021277 (-7900 2250);
DISPLAY INVISIBLE (-7900 2250);
FORCEPROP 1 LAST COMMENT_BODY TRUE
J 0
(-7525 2100);
DISPLAY 0.872340 (-7525 2100);
PAINT GREEN (-7525 2100);
DISPLAY INVISIBLE (-7525 2100);
FORCEPROP 1 LAST OFFPAGE TRUE
J 0
(-7325 2075);
DISPLAY 0.872340 (-7325 2075);
PAINT GREEN (-7325 2075);
DISPLAY INVISIBLE (-7325 2075);
FORCEPROP 2 LAST CDS_LIB mstr_standard
J 0
(-7650 2200);
DISPLAY INVISIBLE (-7650 2200);
FORCEADD CAD_NOTE..1
(-7800 2475);
FORCEPROP 0 LAST L1 R1960 PLACE CLOSE TO CPU < 25MM
J 0
(-7950 2350);
DISPLAY 0.617021 (-7950 2350);
PAINT WHITE (-7950 2350);
FORCEPROP 2 LAST CDS_LIB pure_quanta_power
J 0
(-7800 2475);
DISPLAY INVISIBLE (-7800 2475);
FORCEPROP 1 LAST COMMENT_BODY TRUE
J 0
(-7775 2575);
DISPLAY 0.574468 (-7775 2575);
PAINT WHITE (-7775 2575);
DISPLAY INVISIBLE (-7775 2575);
FORCEADD QUANTA_TITLE_BLOCK_C..1
(-100 100);
FORCEPROP 0 LAST CDS_CON_LAST_MODIFIED Fri Mar 11 14:52:30 2022
J 0
(-1985 115);
DISPLAY INVISIBLE (-1985 115);
FORCEPROP 1 LAST CUSTOM_TXT_CDS <CON_LAST_MODIFIED>
J 0
(-1985 115);
DISPLAY 0.978723 (-1985 115);
FORCEPROP 2 LAST CUSTOM_TXT_CDS <XR_PAGE_TITLE>
J 0
(-7990 5350);
DISPLAY 0.638298 (-7990 5350);
PAINT PINK (-7990 5350);
DISPLAY INVISIBLE (-7990 5350);
FORCEPROP 1 LAST CUSTOM_TXT_CDS <NAME_2>
J 0
(-3275 150);
FORCEPROP 1 LAST CUSTOM_TXT_CDS <NAME_1>
J 0
(-3275 275);
FORCEPROP 1 LAST CUSTOM_TXT_CDS <Q_NUMBER>
J 0
(-1503 203);
DISPLAY 1.212766 (-1503 203);
FORCEPROP 1 LAST CUSTOM_TXT_CDS <Q_PROJ>
J 0
(-2482 202);
DISPLAY 1.212766 (-2482 202);
FORCEPROP 1 LAST CUSTOM_TXT_CDS <Q_REV>
J 0
(-284 203);
DISPLAY 1.212766 (-284 203);
FORCEPROP 1 LAST CUSTOM_TXT_CDS <CON_PAGE_NUM> OF <CON_TOTAL_PAGES>
J 0
(-546 118);
DISPLAY 0.978723 (-546 118);
FORCEPROP 1 LAST Q_TITLE CPU1 DDR CHC
J 0
(-9375 175);
DISPLAY 2.446809 (-9375 175);
PAINT GREEN (-9375 175);
FORCEPROP 1 LAST Q_DEPT BU9
J 1
(-3863 149);
DISPLAY 1.957447 (-3863 149);
PAINT GREEN (-3863 149);
FORCEPROP 2 LAST CDS_LIB pure_quanta
J 0
(-100 100);
DISPLAY INVISIBLE (-100 100);
FORCEPROP 1 LAST CDS_LMAN_SYM_OUTLINE -9475,6775,100,-125
J 0
(-100 100);
DISPLAY 0.468085 (-100 100);
PAINT GREEN (-100 100);
DISPLAY INVISIBLE (-100 100);
FORCEPROP 2 LAST PAGE_BORDER TRUE
J 0
(-7990 5350);
DISPLAY 0.638298 (-7990 5350);
PAINT PINK (-7990 5350);
DISPLAY INVISIBLE (-7990 5350);
FORCEPROP 1 LAST COMMENT_BODY TRUE
J 0
(-88 87);
DISPLAY 0.978723 (-88 87);
PAINT GREEN (-88 87);
DISPLAY INVISIBLE (-88 87);
FORCEPROP 2 LAST CDS_XR_PAGE_TITLE CR-39 : @T6G_MB_LIB.T6G(SCH_1):PAGE39
J 0
(-7990 5350);
DISPLAY 0.638298 (-7990 5350);
PAINT PINK (-7990 5350);
DISPLAY INVISIBLE (-7990 5350);
WIRE 17 -1 (-3425 5325)(-3425 5275);
WIRE 17 -1 (-3425 5375)(-3425 5325);
WIRE 17 -1 (-3425 5175)(-3425 5275);
WIRE 17 -1 (-3425 5125)(-3425 5175);
WIRE 17 -1 (-3425 5425)(-3425 5375);
WIRE 17 -1 (-3425 5475)(-3425 5425);
WIRE 17 -1 (-3425 5075)(-3425 5125);
WIRE 17 -1 (-3425 5025)(-3425 5075);
WIRE 17 -1 (-3425 5525)(-3425 5475);
WIRE 17 -1 (-3425 5575)(-3425 5525);
WIRE 17 -1 (-3425 5025)(-3425 4975);
WIRE 17 -1 (-3425 4975)(-3425 4925);
WIRE 17 -1 (-3425 5625)(-3425 5575);
WIRE 17 -1 (-3425 5725)(-3425 5625);
WIRE 17 -1 (-3425 4925)(-3425 4875);
WIRE 17 -1 (-3425 4875)(-3425 4825);
WIRE 17 -1 (-3425 5775)(-3425 5725);
WIRE 17 -1 (-3425 5825)(-3425 5775);
WIRE 17 -1 (-3425 4825)(-3425 4725);
WIRE 17 -1 (-3425 4725)(-3425 4675);
WIRE 17 -1 (-3425 5875)(-3425 5825);
WIRE 17 -1 (-3425 5925)(-3425 5875);
WIRE 17 -1 (-3425 4675)(-3425 4625);
WIRE 17 -1 (-3425 4625)(-3425 4575);
WIRE 17 -1 (-3425 5975)(-3425 5925);
WIRE 17 -1 (-3425 6025)(-3425 5975);
WIRE 17 -1 (-3425 4525)(-3425 4575);
WIRE 17 -1 (-3425 4475)(-3425 4525);
WIRE 17 -1 (-3425 6075)(-3425 6025);
WIRE 17 -1 (-3425 6075)(-2800 6075);
FORCEPROP 2 LAST SIG_NAME M_C_CPU1_SA_DQ<31:0>
J 2
(-2860 6085);
DISPLAY 0.489362 (-2860 6085);
WIRE 17 -1 (-3425 4425)(-3425 4475);
WIRE 17 -1 (-3425 4375)(-3425 4425);
WIRE 17 -1 (-3425 4275)(-3425 4225);
WIRE 17 -1 (-3425 4275)(-2800 4275);
FORCEPROP 2 LAST SIG_NAME M_C_CPU1_SB_DQ<31:0>
J 2
(-2860 4285);
DISPLAY 0.489362 (-2860 4285);
WIRE 17 -1 (-3425 4225)(-3425 4175);
WIRE 17 -1 (-3425 4175)(-3425 4125);
WIRE 17 -1 (-3425 4125)(-3425 4075);
WIRE 17 -1 (-3425 4075)(-3425 4025);
WIRE 17 -1 (-3425 4025)(-3425 3975);
WIRE 17 -1 (-3425 3975)(-3425 3925);
WIRE 17 -1 (-3425 3925)(-3425 3825);
WIRE 17 -1 (-3425 3825)(-3425 3775);
WIRE 17 -1 (-3425 3775)(-3425 3725);
WIRE 17 -1 (-3425 3725)(-3425 3675);
WIRE 17 -1 (-3425 3675)(-3425 3625);
WIRE 17 -1 (-3425 3625)(-3425 3575);
WIRE 17 -1 (-3425 3575)(-3425 3525);
WIRE 17 -1 (-3425 3525)(-3425 3475);
WIRE 17 -1 (-3425 3375)(-3425 3475);
WIRE 17 -1 (-3425 3325)(-3425 3375);
WIRE 17 -1 (-3425 3175)(-3425 3125);
WIRE 17 -1 (-3425 3225)(-3425 3175);
WIRE 17 -1 (-3425 3125)(-3425 3075);
WIRE 17 -1 (-3425 3075)(-3425 3025);
WIRE 17 -1 (-3425 3225)(-3425 3275);
WIRE 17 -1 (-3425 3275)(-3425 3325);
WIRE 17 -1 (-3425 3025)(-3425 2925);
WIRE 17 -1 (-3425 2925)(-3425 2875);
WIRE 17 -1 (-3425 2875)(-3425 2825);
WIRE 17 -1 (-3425 2825)(-3425 2775);
WIRE 17 -1 (-3425 2725)(-3425 2775);
WIRE 17 -1 (-3425 2675)(-3425 2725);
WIRE 17 -1 (-3425 2625)(-3425 2675);
WIRE 17 -1 (-3425 2575)(-3425 2625);
WIRE 17 -1 (-3425 2225)(-3425 2275);
WIRE 17 -1 (-3425 2175)(-3425 2225);
WIRE 17 -1 (-3425 2275)(-3425 2325);
WIRE 17 -1 (-3425 2375)(-3425 2325);
WIRE 17 -1 (-3425 2125)(-3425 2175);
WIRE 17 -1 (-3425 2375)(-3425 2425);
WIRE 17 -1 (-3425 2475)(-3425 2425);
WIRE 17 -1 (-3425 2475)(-3425 2500);
WIRE 17 -1 (-3425 2500)(-2925 2500);
FORCEPROP 2 LAST SIG_NAME M_C_CPU1_SA_CB<7:0>
J 2
(-2925 2510);
DISPLAY 0.489362 (-2925 2510);
WIRE 17 -1 (-3425 2025)(-3425 1975);
WIRE 17 -1 (-3425 2025)(-3425 2050);
WIRE 17 -1 (-3425 1925)(-3425 1975);
WIRE 17 -1 (-3425 1925)(-3425 1875);
WIRE 17 -1 (-3425 2050)(-2925 2050);
FORCEPROP 2 LAST SIG_NAME M_C_CPU1_SB_CB<7:0>
J 2
(-2925 2060);
DISPLAY 0.489362 (-2925 2060);
WIRE 17 -1 (-3425 1825)(-3425 1875);
WIRE 17 -1 (-3425 1775)(-3425 1825);
WIRE 17 -1 (-3425 1725)(-3425 1775);
WIRE 17 -1 (-3425 1675)(-3425 1725);
WIRE 17 -1 (-6150 6025)(-6150 5925);
FORCEPROP 2 LAST SIG_NAME M_C_CPU1_SA_DQS_DN<9:0>
J 2
(-6185 6035);
DISPLAY 0.489362 (-6185 6035);
WIRE 17 -1 (-6150 5825)(-6150 5725);
WIRE 17 -1 (-6150 5925)(-6150 5825);
WIRE 17 -1 (-6150 5725)(-6150 5625);
WIRE 17 -1 (-6150 5525)(-6150 5625);
WIRE 17 -1 (-6150 5425)(-6150 5525);
WIRE 17 -1 (-6150 5325)(-6150 5425);
WIRE 17 -1 (-6150 5325)(-6150 5225);
WIRE 17 -1 (-5950 6075)(-5950 5975);
WIRE 17 -1 (-5950 6075)(-6750 6075);
FORCEPROP 2 LAST SIG_NAME M_C_CPU1_SA_DQS_DP<9:0>
J 2
(-6185 6085);
DISPLAY 0.489362 (-6185 6085);
WIRE 17 -1 (-6150 5225)(-6150 5125);
WIRE 17 -1 (-5950 5975)(-5950 5875);
WIRE 17 -1 (-5950 5875)(-5950 5775);
WIRE 17 -1 (-5950 5775)(-5950 5675);
WIRE 17 -1 (-5950 5575)(-5950 5675);
WIRE 17 -1 (-5950 5475)(-5950 5575);
WIRE 17 -1 (-5950 5375)(-5950 5475);
WIRE 17 -1 (-5950 5375)(-5950 5275);
WIRE 17 -1 (-5950 5275)(-5950 5175);
WIRE 17 -1 (-5950 4325)(-5950 4225);
WIRE 17 -1 (-5950 4325)(-5950 4425);
WIRE 17 -1 (-5950 4225)(-5950 4125);
WIRE 17 -1 (-5950 4425)(-5950 4525);
WIRE 17 -1 (-5950 4525)(-5950 4625);
WIRE 17 -1 (-5950 4725)(-5950 4625);
WIRE 17 -1 (-5950 4825)(-5950 4725);
WIRE 17 -1 (-5950 4925)(-5950 4825);
WIRE 17 -1 (-5950 5025)(-5950 4925);
WIRE 17 -1 (-5950 5025)(-6750 5025);
FORCEPROP 2 LAST SIG_NAME M_C_CPU1_SB_DQS_DP<9:0>
J 2
(-6185 5035);
DISPLAY 0.489362 (-6185 5035);
WIRE 17 -1 (-6150 4975)(-6150 4875);
FORCEPROP 2 LAST SIG_NAME M_C_CPU1_SB_DQS_DN<9:0>
J 2
(-6185 4985);
DISPLAY 0.489362 (-6185 4985);
WIRE 17 -1 (-6150 4775)(-6150 4675);
WIRE 17 -1 (-6150 4875)(-6150 4775);
WIRE 17 -1 (-6150 4675)(-6150 4575);
WIRE 17 -1 (-6150 4475)(-6150 4575);
WIRE 17 -1 (-6150 4375)(-6150 4475);
WIRE 17 -1 (-6150 4275)(-6150 4375);
WIRE 17 -1 (-6150 4275)(-6150 4175);
WIRE 17 -1 (-6150 4175)(-6150 4075);
WIRE 17 -1 (-6150 3875)(-6150 3925);
WIRE 17 -1 (-6150 3825)(-6150 3875);
WIRE 17 -1 (-6150 3925)(-6650 3925);
FORCEPROP 2 LAST SIG_NAME M_C_CPU1_SA_CA<6:0>
J 0
(-6650 3935);
DISPLAY 0.489362 (-6650 3935);
WIRE 17 -1 (-6150 3475)(-6150 3525);
WIRE 17 -1 (-6150 3425)(-6150 3475);
WIRE 17 -1 (-6150 3525)(-6650 3525);
FORCEPROP 2 LAST SIG_NAME M_C_CPU1_SB_CA<6:0>
J 0
(-6650 3535);
DISPLAY 0.489362 (-6650 3535);
WIRE 17 -1 (-6150 3775)(-6150 3825);
WIRE 17 -1 (-6150 3375)(-6150 3425);
WIRE 17 -1 (-6150 3725)(-6150 3775);
WIRE 17 -1 (-6150 3675)(-6150 3725);
WIRE 17 -1 (-6150 3625)(-6150 3675);
WIRE 17 -1 (-6150 3325)(-6150 3375);
WIRE 17 -1 (-6150 3275)(-6150 3325);
WIRE 17 -1 (-6150 3225)(-6150 3275);
WIRE 17 -1 (-6150 6025)(-6750 6025);
WIRE 17 -1 (-6150 4975)(-6750 4975);
WIRE 16 -1 (-7600 2200)(-6875 2200);
FORCEPROP 2 LAST SIG_NAME M_C_CPU1_ALERT_N
J 0
(-7560 2210);
DISPLAY 0.489362 (-7560 2210);
WIRE 16 -1 (-6650 1250)(-5550 1250);
FORCEPROP 2 LAST SIG_NAME TP_M_C_CPU1_SA_TEST39C
J 0
(-6635 1260);
DISPLAY 0.489362 (-6635 1260);
FORCEPROP 2 LASTPROP $XRERR UNIQUE?
J 0
(-6890 1250);
DISPLAY 0.638298 (-6890 1250);
PAINT MONO (-6890 1250);
DISPLAY INVISIBLE (-6890 1250);
WIRE 16 -1 (-6675 2200)(-5550 2200);
FORCEPROP 2 LAST SIG_NAME M_C_CPU1_ALERT_R_N
J 0
(-6385 2210);
DISPLAY 0.489362 (-6385 2210);
FORCEPROP 2 LASTPROP $XRERR UNIQUE?
J 0
(-6625 2210);
DISPLAY 0.638298 (-6625 2210);
PAINT MONO (-6625 2210);
DISPLAY INVISIBLE (-6625 2210);
WIRE 16 -1 (-6650 3000)(-5550 3000);
FORCEPROP 2 LAST SIG_NAME M_C_CPU1_CLK_DN<0>
J 0
(-6650 3010);
DISPLAY 0.489362 (-6650 3010);
WIRE 16 -1 (-6650 3050)(-5550 3050);
FORCEPROP 2 LAST SIG_NAME M_C_CPU1_CLK_DP<0>
J 0
(-6650 3060);
DISPLAY 0.489362 (-6650 3060);
WIRE 16 -1 (-6650 2850)(-5550 2850);
FORCEPROP 2 LAST SIG_NAME M_C_CPU1_SA_CS_N<1>
J 0
(-6650 2860);
DISPLAY 0.489362 (-6650 2860);
WIRE 16 -1 (-6650 2900)(-5550 2900);
FORCEPROP 2 LAST SIG_NAME M_C_CPU1_SA_CS_N<0>
J 0
(-6650 2910);
DISPLAY 0.489362 (-6650 2910);
WIRE 16 -1 (-6650 2750)(-5550 2750);
FORCEPROP 2 LAST SIG_NAME M_C_CPU1_SA_RSP<0>
J 0
(-6650 2760);
DISPLAY 0.489362 (-6650 2760);
WIRE 16 -1 (-6650 2650)(-5550 2650);
FORCEPROP 2 LAST SIG_NAME M_C_CPU1_SA_PAR
J 0
(-6650 2660);
DISPLAY 0.489362 (-6650 2660);
WIRE 16 -1 (-6650 2550)(-5550 2550);
FORCEPROP 2 LAST SIG_NAME M_C_CPU1_SB_CS_N<0>
J 0
(-6650 2560);
DISPLAY 0.489362 (-6650 2560);
WIRE 16 -1 (-6650 2500)(-5550 2500);
FORCEPROP 2 LAST SIG_NAME M_C_CPU1_SB_CS_N<1>
J 0
(-6650 2510);
DISPLAY 0.489362 (-6650 2510);
WIRE 16 -1 (-6650 2400)(-5550 2400);
FORCEPROP 2 LAST SIG_NAME M_C_CPU1_SB_RSP<0>
J 0
(-6650 2410);
DISPLAY 0.489362 (-6650 2410);
WIRE 16 -1 (-6650 2300)(-5550 2300);
FORCEPROP 2 LAST SIG_NAME M_C_CPU1_SB_PAR
J 0
(-6650 2310);
DISPLAY 0.489362 (-6650 2310);
WIRE 16 -1 (-6650 2100)(-5550 2100);
FORCEPROP 2 LAST SIG_NAME M_C_CPU1_RESET_N
J 0
(-6650 2110);
DISPLAY 0.489362 (-6650 2110);
WIRE 16 -1 (-6050 3200)(-5550 3200);
WIRE 16 -1 (-6050 4050)(-5550 4050);
WIRE 16 -1 (-6050 3600)(-5550 3600);
WIRE 16 -1 (-6050 3250)(-5550 3250);
WIRE 16 -1 (-6050 3650)(-5550 3650);
WIRE 16 -1 (-6050 3300)(-5550 3300);
WIRE 16 -1 (-6050 3700)(-5550 3700);
WIRE 16 -1 (-6050 3350)(-5550 3350);
WIRE 16 -1 (-6050 3750)(-5550 3750);
WIRE 16 -1 (-6050 3400)(-5550 3400);
WIRE 16 -1 (-6050 3800)(-5550 3800);
WIRE 16 -1 (-6050 3450)(-5550 3450);
WIRE 16 -1 (-6050 3850)(-5550 3850);
WIRE 16 -1 (-6050 3500)(-5550 3500);
WIRE 16 -1 (-6050 3900)(-5550 3900);
WIRE 16 -1 (-5850 4100)(-5550 4100);
WIRE 16 -1 (-5850 4300)(-5550 4300);
WIRE 16 -1 (-5850 4400)(-5550 4400);
WIRE 16 -1 (-5850 4500)(-5550 4500);
WIRE 16 -1 (-5850 4600)(-5550 4600);
WIRE 16 -1 (-6050 4150)(-5550 4150);
WIRE 16 -1 (-5850 4700)(-5550 4700);
WIRE 16 -1 (-6050 4250)(-5550 4250);
WIRE 16 -1 (-5850 4800)(-5550 4800);
WIRE 16 -1 (-6050 4350)(-5550 4350);
WIRE 16 -1 (-5850 4900)(-5550 4900);
WIRE 16 -1 (-6050 4450)(-5550 4450);
WIRE 16 -1 (-5850 5000)(-5550 5000);
WIRE 16 -1 (-6050 4550)(-5550 4550);
WIRE 16 -1 (-6050 5100)(-5550 5100);
WIRE 16 -1 (-6050 4650)(-5550 4650);
WIRE 16 -1 (-6050 4750)(-5550 4750);
WIRE 16 -1 (-6050 4850)(-5550 4850);
WIRE 16 -1 (-6050 4950)(-5550 4950);
WIRE 16 -1 (-5850 4200)(-5550 4200);
WIRE 16 -1 (-6050 6000)(-5550 6000);
WIRE 16 -1 (-5850 5150)(-5550 5150);
WIRE 16 -1 (-5850 5250)(-5550 5250);
WIRE 16 -1 (-5850 5350)(-5550 5350);
WIRE 16 -1 (-5850 5450)(-5550 5450);
WIRE 16 -1 (-5850 5550)(-5550 5550);
WIRE 16 -1 (-5850 5650)(-5550 5650);
WIRE 16 -1 (-6050 5200)(-5550 5200);
WIRE 16 -1 (-5850 5750)(-5550 5750);
WIRE 16 -1 (-6050 5300)(-5550 5300);
WIRE 16 -1 (-5850 5850)(-5550 5850);
WIRE 16 -1 (-6050 5400)(-5550 5400);
WIRE 16 -1 (-5850 5950)(-5550 5950);
WIRE 16 -1 (-6050 5500)(-5550 5500);
WIRE 16 -1 (-5850 6050)(-5550 6050);
WIRE 16 -1 (-6050 5600)(-5550 5600);
WIRE 16 -1 (-6050 5700)(-5550 5700);
WIRE 16 -1 (-6050 5800)(-5550 5800);
WIRE 16 -1 (-6050 5900)(-5550 5900);
WIRE 16 -1 (-3950 1650)(-3525 1650);
WIRE 16 -1 (-3525 1700)(-3950 1700);
WIRE 16 -1 (-3950 1750)(-3525 1750);
WIRE 16 -1 (-3950 1800)(-3525 1800);
WIRE 16 -1 (-3525 1850)(-3950 1850);
WIRE 16 -1 (-3950 1900)(-3525 1900);
WIRE 16 -1 (-3950 1950)(-3525 1950);
WIRE 16 -1 (-3950 2000)(-3525 2000);
WIRE 16 -1 (-3950 2250)(-3525 2250);
WIRE 16 -1 (-3950 2300)(-3525 2300);
WIRE 16 -1 (-3950 2350)(-3525 2350);
WIRE 16 -1 (-3950 2400)(-3525 2400);
WIRE 16 -1 (-3950 2450)(-3525 2450);
WIRE 16 -1 (-3950 2650)(-3525 2650);
WIRE 16 -1 (-3950 2700)(-3525 2700);
WIRE 16 -1 (-3950 2750)(-3525 2750);
WIRE 16 -1 (-3950 2800)(-3525 2800);
WIRE 16 -1 (-3950 2850)(-3525 2850);
WIRE 16 -1 (-3950 2900)(-3525 2900);
WIRE 16 -1 (-3950 3000)(-3525 3000);
WIRE 16 -1 (-3950 3050)(-3525 3050);
WIRE 16 -1 (-3950 2100)(-3525 2100);
WIRE 16 -1 (-3950 2150)(-3525 2150);
WIRE 16 -1 (-3950 2550)(-3525 2550);
WIRE 16 -1 (-3950 2200)(-3525 2200);
WIRE 16 -1 (-3950 2600)(-3525 2600);
WIRE 16 -1 (-3950 3900)(-3525 3900);
WIRE 16 -1 (-3950 3950)(-3525 3950);
WIRE 16 -1 (-3950 4000)(-3525 4000);
WIRE 16 -1 (-3950 4050)(-3525 4050);
WIRE 16 -1 (-3950 3200)(-3525 3200);
WIRE 16 -1 (-3950 3250)(-3525 3250);
WIRE 16 -1 (-3950 3300)(-3525 3300);
WIRE 16 -1 (-3950 3350)(-3525 3350);
WIRE 16 -1 (-3950 3450)(-3525 3450);
WIRE 16 -1 (-3950 3500)(-3525 3500);
WIRE 16 -1 (-3950 3550)(-3525 3550);
WIRE 16 -1 (-3950 3600)(-3525 3600);
WIRE 16 -1 (-3950 3650)(-3525 3650);
WIRE 16 -1 (-3950 3700)(-3525 3700);
WIRE 16 -1 (-3950 3100)(-3525 3100);
WIRE 16 -1 (-3950 3750)(-3525 3750);
WIRE 16 -1 (-3950 3150)(-3525 3150);
WIRE 16 -1 (-3950 3800)(-3525 3800);
WIRE 16 -1 (-3950 4700)(-3525 4700);
WIRE 16 -1 (-3950 4800)(-3525 4800);
WIRE 16 -1 (-3950 4850)(-3525 4850);
WIRE 16 -1 (-3950 4900)(-3525 4900);
WIRE 16 -1 (-3950 4950)(-3525 4950);
WIRE 16 -1 (-3950 4350)(-3525 4350);
WIRE 16 -1 (-3950 4100)(-3525 4100);
WIRE 16 -1 (-3950 4400)(-3525 4400);
WIRE 16 -1 (-3950 4150)(-3525 4150);
WIRE 16 -1 (-3950 4200)(-3525 4200);
WIRE 16 -1 (-3950 4250)(-3525 4250);
WIRE 16 -1 (-3950 5000)(-3525 5000);
WIRE 16 -1 (-3950 5050)(-3525 5050);
WIRE 16 -1 (-3950 4450)(-3525 4450);
WIRE 16 -1 (-3950 5100)(-3525 5100);
WIRE 16 -1 (-3950 4500)(-3525 4500);
WIRE 16 -1 (-3950 4550)(-3525 4550);
WIRE 16 -1 (-3950 4600)(-3525 4600);
WIRE 16 -1 (-3950 4650)(-3525 4650);
WIRE 16 -1 (-3950 5600)(-3525 5600);
WIRE 16 -1 (-3950 5350)(-3525 5350);
WIRE 16 -1 (-3950 5700)(-3525 5700);
WIRE 16 -1 (-3950 5400)(-3525 5400);
WIRE 16 -1 (-3950 5750)(-3525 5750);
WIRE 16 -1 (-3950 5450)(-3525 5450);
WIRE 16 -1 (-3950 5800)(-3525 5800);
WIRE 16 -1 (-3950 5500)(-3525 5500);
WIRE 16 -1 (-3950 5850)(-3525 5850);
WIRE 16 -1 (-3950 5900)(-3525 5900);
WIRE 16 -1 (-3950 5950)(-3525 5950);
WIRE 16 -1 (-3950 6000)(-3525 6000);
WIRE 16 -1 (-3950 6050)(-3525 6050);
WIRE 16 -1 (-3950 5150)(-3525 5150);
WIRE 16 -1 (-3950 5250)(-3525 5250);
WIRE 16 -1 (-3950 5550)(-3525 5550);
WIRE 16 -1 (-3950 5300)(-3525 5300);
QUIT
